FILE_TYPE = MACRO_DRAWING;
SET COLOR_WIRE YELLOW;
SET COLOR_PROP ORANGE;
SET COLOR_DOT WHITE;
SET COLOR_ARC YELLOW;
SET COLOR_BODY GREEN;
SET COLOR_NOTE PURPLE;
SET PROP_DISPLAY VALUE;
SET PAGE_NUMBER P21;
FORCEADD TAP..1
R 2
(-175 75);
FORCEPROP 3 LASTPIN (-125 75) SIG_NAME M_B_CPU0_SB_CB<1>
J 0
(-115 85);
DISPLAY 0.659574 (-115 85);
PAINT MONO (-115 85);
DISPLAY INVISIBLE (-115 85);
FORCEPROP 1 LASTPIN (-125 75) BN 1
J 2
(-113 83);
DISPLAY 0.680851 (-113 83);
PAINT GREEN (-113 83);
FORCEPROP 2 LAST CDS_LIB standard
J 0
(-175 75);
DISPLAY INVISIBLE (-175 75);
FORCEPROP 1 LAST BODY_TYPE PLUMBING
J 2
(-175 125);
DISPLAY 0.872340 (-175 125);
PAINT GREEN (-175 125);
DISPLAY INVISIBLE (-175 125);
FORCEPROP 1 LAST HDL_TAP TRUE
J 2
(-500 -50);
DISPLAY 0.872340 (-500 -50);
DISPLAY INVISIBLE (-500 -50);
FORCEPROP 1 LAST PATH I10
J 2
(-173 75);
DISPLAY 0.872340 (-173 75);
PAINT GREEN (-173 75);
DISPLAY INVISIBLE (-173 75);
FORCEADD TAP..1
(3250 675);
FORCEPROP 3 LASTPIN (3200 675) SIG_NAME M_B_CPU0_SA_CS_N<3>
J 0
(3210 685);
DISPLAY 0.659574 (3210 685);
PAINT MONO (3210 685);
DISPLAY INVISIBLE (3210 685);
FORCEPROP 1 LASTPIN (3200 675) BN 3
J 0
(3188 683);
DISPLAY 0.680851 (3188 683);
PAINT GREEN (3188 683);
FORCEPROP 2 LAST CDS_LIB standard
J 0
(3250 675);
DISPLAY INVISIBLE (3250 675);
FORCEPROP 1 LAST BODY_TYPE PLUMBING
J 0
(3250 725);
DISPLAY 0.872340 (3250 725);
PAINT GREEN (3250 725);
DISPLAY INVISIBLE (3250 725);
FORCEPROP 1 LAST HDL_TAP TRUE
J 0
(3575 550);
DISPLAY 0.872340 (3575 550);
DISPLAY INVISIBLE (3575 550);
FORCEPROP 1 LAST PATH I100
J 0
(3248 675);
DISPLAY 0.872340 (3248 675);
PAINT GREEN (3248 675);
DISPLAY INVISIBLE (3248 675);
FORCEADD TAP..1
(3250 925);
FORCEPROP 3 LASTPIN (3200 925) SIG_NAME M_B_CPU0_SB_CA<1>
J 0
(3210 935);
DISPLAY 0.659574 (3210 935);
PAINT MONO (3210 935);
DISPLAY INVISIBLE (3210 935);
FORCEPROP 1 LASTPIN (3200 925) BN 1
J 0
(3188 933);
DISPLAY 0.680851 (3188 933);
PAINT GREEN (3188 933);
FORCEPROP 2 LAST CDS_LIB standard
J 0
(3250 925);
DISPLAY INVISIBLE (3250 925);
FORCEPROP 1 LAST BODY_TYPE PLUMBING
J 0
(3250 975);
DISPLAY 0.872340 (3250 975);
PAINT GREEN (3250 975);
DISPLAY INVISIBLE (3250 975);
FORCEPROP 1 LAST HDL_TAP TRUE
J 0
(3575 800);
DISPLAY 0.872340 (3575 800);
DISPLAY INVISIBLE (3575 800);
FORCEPROP 1 LAST PATH I101
J 0
(3248 925);
DISPLAY 0.872340 (3248 925);
PAINT GREEN (3248 925);
DISPLAY INVISIBLE (3248 925);
FORCEADD TAP..1
(3250 875);
FORCEPROP 3 LASTPIN (3200 875) SIG_NAME M_B_CPU0_SB_CA<0>
J 0
(3210 885);
DISPLAY 0.659574 (3210 885);
PAINT MONO (3210 885);
DISPLAY INVISIBLE (3210 885);
FORCEPROP 1 LASTPIN (3200 875) BN 0
J 0
(3188 883);
DISPLAY 0.680851 (3188 883);
PAINT GREEN (3188 883);
FORCEPROP 2 LAST CDS_LIB standard
J 0
(3250 875);
DISPLAY INVISIBLE (3250 875);
FORCEPROP 1 LAST BODY_TYPE PLUMBING
J 0
(3250 925);
DISPLAY 0.872340 (3250 925);
PAINT GREEN (3250 925);
DISPLAY INVISIBLE (3250 925);
FORCEPROP 1 LAST HDL_TAP TRUE
J 0
(3575 750);
DISPLAY 0.872340 (3575 750);
DISPLAY INVISIBLE (3575 750);
FORCEPROP 1 LAST PATH I102
J 0
(3248 875);
DISPLAY 0.872340 (3248 875);
PAINT GREEN (3248 875);
DISPLAY INVISIBLE (3248 875);
FORCEADD TAP..1
(3250 975);
FORCEPROP 3 LASTPIN (3200 975) SIG_NAME M_B_CPU0_SB_CA<2>
J 0
(3210 985);
DISPLAY 0.659574 (3210 985);
PAINT MONO (3210 985);
DISPLAY INVISIBLE (3210 985);
FORCEPROP 1 LASTPIN (3200 975) BN 2
J 0
(3188 983);
DISPLAY 0.680851 (3188 983);
PAINT GREEN (3188 983);
FORCEPROP 2 LAST CDS_LIB standard
J 0
(3250 975);
DISPLAY INVISIBLE (3250 975);
FORCEPROP 1 LAST BODY_TYPE PLUMBING
J 0
(3250 1025);
DISPLAY 0.872340 (3250 1025);
PAINT GREEN (3250 1025);
DISPLAY INVISIBLE (3250 1025);
FORCEPROP 1 LAST HDL_TAP TRUE
J 0
(3575 850);
DISPLAY 0.872340 (3575 850);
DISPLAY INVISIBLE (3575 850);
FORCEPROP 1 LAST PATH I103
J 0
(3248 975);
DISPLAY 0.872340 (3248 975);
PAINT GREEN (3248 975);
DISPLAY INVISIBLE (3248 975);
FORCEADD TAP..1
(3250 1025);
FORCEPROP 3 LASTPIN (3200 1025) SIG_NAME M_B_CPU0_SB_CA<3>
J 0
(3210 1035);
DISPLAY 0.659574 (3210 1035);
PAINT MONO (3210 1035);
DISPLAY INVISIBLE (3210 1035);
FORCEPROP 1 LASTPIN (3200 1025) BN 3
J 0
(3188 1033);
DISPLAY 0.680851 (3188 1033);
PAINT GREEN (3188 1033);
FORCEPROP 2 LAST CDS_LIB standard
J 0
(3250 1025);
DISPLAY INVISIBLE (3250 1025);
FORCEPROP 1 LAST BODY_TYPE PLUMBING
J 0
(3250 1075);
DISPLAY 0.872340 (3250 1075);
PAINT GREEN (3250 1075);
DISPLAY INVISIBLE (3250 1075);
FORCEPROP 1 LAST HDL_TAP TRUE
J 0
(3575 900);
DISPLAY 0.872340 (3575 900);
DISPLAY INVISIBLE (3575 900);
FORCEPROP 1 LAST PATH I104
J 0
(3248 1025);
DISPLAY 0.872340 (3248 1025);
PAINT GREEN (3248 1025);
DISPLAY INVISIBLE (3248 1025);
FORCEADD TAP..1
(3250 1175);
FORCEPROP 3 LASTPIN (3200 1175) SIG_NAME M_B_CPU0_SB_CA<6>
J 0
(3210 1185);
DISPLAY 0.659574 (3210 1185);
PAINT MONO (3210 1185);
DISPLAY INVISIBLE (3210 1185);
FORCEPROP 1 LASTPIN (3200 1175) BN 6
J 0
(3188 1183);
DISPLAY 0.680851 (3188 1183);
PAINT GREEN (3188 1183);
FORCEPROP 2 LAST CDS_LIB standard
J 0
(3250 1175);
DISPLAY INVISIBLE (3250 1175);
FORCEPROP 1 LAST BODY_TYPE PLUMBING
J 0
(3250 1225);
DISPLAY 0.872340 (3250 1225);
PAINT GREEN (3250 1225);
DISPLAY INVISIBLE (3250 1225);
FORCEPROP 1 LAST HDL_TAP TRUE
J 0
(3575 1050);
DISPLAY 0.872340 (3575 1050);
DISPLAY INVISIBLE (3575 1050);
FORCEPROP 1 LAST PATH I105
J 0
(3248 1175);
DISPLAY 0.872340 (3248 1175);
PAINT GREEN (3248 1175);
DISPLAY INVISIBLE (3248 1175);
FORCEADD TAP..1
(3250 1125);
FORCEPROP 3 LASTPIN (3200 1125) SIG_NAME M_B_CPU0_SB_CA<5>
J 0
(3210 1135);
DISPLAY 0.659574 (3210 1135);
PAINT MONO (3210 1135);
DISPLAY INVISIBLE (3210 1135);
FORCEPROP 1 LASTPIN (3200 1125) BN 5
J 0
(3188 1133);
DISPLAY 0.680851 (3188 1133);
PAINT GREEN (3188 1133);
FORCEPROP 2 LAST CDS_LIB standard
J 0
(3250 1125);
DISPLAY INVISIBLE (3250 1125);
FORCEPROP 1 LAST BODY_TYPE PLUMBING
J 0
(3250 1175);
DISPLAY 0.872340 (3250 1175);
PAINT GREEN (3250 1175);
DISPLAY INVISIBLE (3250 1175);
FORCEPROP 1 LAST HDL_TAP TRUE
J 0
(3575 1000);
DISPLAY 0.872340 (3575 1000);
DISPLAY INVISIBLE (3575 1000);
FORCEPROP 1 LAST PATH I106
J 0
(3248 1125);
DISPLAY 0.872340 (3248 1125);
PAINT GREEN (3248 1125);
DISPLAY INVISIBLE (3248 1125);
FORCEADD TAP..1
(3250 1075);
FORCEPROP 3 LASTPIN (3200 1075) SIG_NAME M_B_CPU0_SB_CA<4>
J 0
(3210 1085);
DISPLAY 0.659574 (3210 1085);
PAINT MONO (3210 1085);
DISPLAY INVISIBLE (3210 1085);
FORCEPROP 1 LASTPIN (3200 1075) BN 4
J 0
(3188 1083);
DISPLAY 0.680851 (3188 1083);
PAINT GREEN (3188 1083);
FORCEPROP 2 LAST CDS_LIB standard
J 0
(3250 1075);
DISPLAY INVISIBLE (3250 1075);
FORCEPROP 1 LAST BODY_TYPE PLUMBING
J 0
(3250 1125);
DISPLAY 0.872340 (3250 1125);
PAINT GREEN (3250 1125);
DISPLAY INVISIBLE (3250 1125);
FORCEPROP 1 LAST HDL_TAP TRUE
J 0
(3575 950);
DISPLAY 0.872340 (3575 950);
DISPLAY INVISIBLE (3575 950);
FORCEPROP 1 LAST PATH I107
J 0
(3248 1075);
DISPLAY 0.872340 (3248 1075);
PAINT GREEN (3248 1075);
DISPLAY INVISIBLE (3248 1075);
FORCEADD TAP..1
(3250 1375);
FORCEPROP 3 LASTPIN (3200 1375) SIG_NAME M_B_CPU0_SA_CA<0>
J 0
(3210 1385);
DISPLAY 0.659574 (3210 1385);
PAINT MONO (3210 1385);
DISPLAY INVISIBLE (3210 1385);
FORCEPROP 1 LASTPIN (3200 1375) BN 0
J 0
(3188 1383);
DISPLAY 0.680851 (3188 1383);
PAINT GREEN (3188 1383);
FORCEPROP 2 LAST CDS_LIB standard
J 0
(3250 1375);
DISPLAY INVISIBLE (3250 1375);
FORCEPROP 1 LAST BODY_TYPE PLUMBING
J 0
(3250 1425);
DISPLAY 0.872340 (3250 1425);
PAINT GREEN (3250 1425);
DISPLAY INVISIBLE (3250 1425);
FORCEPROP 1 LAST HDL_TAP TRUE
J 0
(3575 1250);
DISPLAY 0.872340 (3575 1250);
DISPLAY INVISIBLE (3575 1250);
FORCEPROP 1 LAST PATH I108
J 0
(3248 1375);
DISPLAY 0.872340 (3248 1375);
PAINT GREEN (3248 1375);
DISPLAY INVISIBLE (3248 1375);
FORCEADD TAP..1
(3250 1425);
FORCEPROP 3 LASTPIN (3200 1425) SIG_NAME M_B_CPU0_SA_CA<1>
J 0
(3210 1435);
DISPLAY 0.659574 (3210 1435);
PAINT MONO (3210 1435);
DISPLAY INVISIBLE (3210 1435);
FORCEPROP 1 LASTPIN (3200 1425) BN 1
J 0
(3188 1433);
DISPLAY 0.680851 (3188 1433);
PAINT GREEN (3188 1433);
FORCEPROP 2 LAST CDS_LIB standard
J 0
(3250 1425);
DISPLAY INVISIBLE (3250 1425);
FORCEPROP 1 LAST BODY_TYPE PLUMBING
J 0
(3250 1475);
DISPLAY 0.872340 (3250 1475);
PAINT GREEN (3250 1475);
DISPLAY INVISIBLE (3250 1475);
FORCEPROP 1 LAST HDL_TAP TRUE
J 0
(3575 1300);
DISPLAY 0.872340 (3575 1300);
DISPLAY INVISIBLE (3575 1300);
FORCEPROP 1 LAST PATH I109
J 0
(3248 1425);
DISPLAY 0.872340 (3248 1425);
PAINT GREEN (3248 1425);
DISPLAY INVISIBLE (3248 1425);
FORCEADD TAP..1
R 2
(-175 125);
FORCEPROP 3 LASTPIN (-125 125) SIG_NAME M_B_CPU0_SB_CB<2>
J 0
(-115 135);
DISPLAY 0.659574 (-115 135);
PAINT MONO (-115 135);
DISPLAY INVISIBLE (-115 135);
FORCEPROP 1 LASTPIN (-125 125) BN 2
J 2
(-113 133);
DISPLAY 0.680851 (-113 133);
PAINT GREEN (-113 133);
FORCEPROP 2 LAST CDS_LIB standard
J 0
(-175 125);
DISPLAY INVISIBLE (-175 125);
FORCEPROP 1 LAST BODY_TYPE PLUMBING
J 2
(-175 175);
DISPLAY 0.872340 (-175 175);
PAINT GREEN (-175 175);
DISPLAY INVISIBLE (-175 175);
FORCEPROP 1 LAST HDL_TAP TRUE
J 2
(-500 0);
DISPLAY 0.872340 (-500 0);
DISPLAY INVISIBLE (-500 0);
FORCEPROP 1 LAST PATH I11
J 2
(-173 125);
DISPLAY 0.872340 (-173 125);
PAINT GREEN (-173 125);
DISPLAY INVISIBLE (-173 125);
FORCEADD TAP..1
(3250 1475);
FORCEPROP 3 LASTPIN (3200 1475) SIG_NAME M_B_CPU0_SA_CA<2>
J 0
(3210 1485);
DISPLAY 0.659574 (3210 1485);
PAINT MONO (3210 1485);
DISPLAY INVISIBLE (3210 1485);
FORCEPROP 1 LASTPIN (3200 1475) BN 2
J 0
(3188 1483);
DISPLAY 0.680851 (3188 1483);
PAINT GREEN (3188 1483);
FORCEPROP 2 LAST CDS_LIB standard
J 0
(3250 1475);
DISPLAY INVISIBLE (3250 1475);
FORCEPROP 1 LAST BODY_TYPE PLUMBING
J 0
(3250 1525);
DISPLAY 0.872340 (3250 1525);
PAINT GREEN (3250 1525);
DISPLAY INVISIBLE (3250 1525);
FORCEPROP 1 LAST HDL_TAP TRUE
J 0
(3575 1350);
DISPLAY 0.872340 (3575 1350);
DISPLAY INVISIBLE (3575 1350);
FORCEPROP 1 LAST PATH I110
J 0
(3248 1475);
DISPLAY 0.872340 (3248 1475);
PAINT GREEN (3248 1475);
DISPLAY INVISIBLE (3248 1475);
FORCEADD TAP..1
(3250 1525);
FORCEPROP 3 LASTPIN (3200 1525) SIG_NAME M_B_CPU0_SA_CA<3>
J 0
(3210 1535);
DISPLAY 0.659574 (3210 1535);
PAINT MONO (3210 1535);
DISPLAY INVISIBLE (3210 1535);
FORCEPROP 1 LASTPIN (3200 1525) BN 3
J 0
(3188 1533);
DISPLAY 0.680851 (3188 1533);
PAINT GREEN (3188 1533);
FORCEPROP 2 LAST CDS_LIB standard
J 0
(3250 1525);
DISPLAY INVISIBLE (3250 1525);
FORCEPROP 1 LAST BODY_TYPE PLUMBING
J 0
(3250 1575);
DISPLAY 0.872340 (3250 1575);
PAINT GREEN (3250 1575);
DISPLAY INVISIBLE (3250 1575);
FORCEPROP 1 LAST HDL_TAP TRUE
J 0
(3575 1400);
DISPLAY 0.872340 (3575 1400);
DISPLAY INVISIBLE (3575 1400);
FORCEPROP 1 LAST PATH I111
J 0
(3248 1525);
DISPLAY 0.872340 (3248 1525);
PAINT GREEN (3248 1525);
DISPLAY INVISIBLE (3248 1525);
FORCEADD TAP..1
(3250 1575);
FORCEPROP 3 LASTPIN (3200 1575) SIG_NAME M_B_CPU0_SA_CA<4>
J 0
(3210 1585);
DISPLAY 0.659574 (3210 1585);
PAINT MONO (3210 1585);
DISPLAY INVISIBLE (3210 1585);
FORCEPROP 1 LASTPIN (3200 1575) BN 4
J 0
(3188 1583);
DISPLAY 0.680851 (3188 1583);
PAINT GREEN (3188 1583);
FORCEPROP 2 LAST CDS_LIB standard
J 0
(3250 1575);
DISPLAY INVISIBLE (3250 1575);
FORCEPROP 1 LAST BODY_TYPE PLUMBING
J 0
(3250 1625);
DISPLAY 0.872340 (3250 1625);
PAINT GREEN (3250 1625);
DISPLAY INVISIBLE (3250 1625);
FORCEPROP 1 LAST HDL_TAP TRUE
J 0
(3575 1450);
DISPLAY 0.872340 (3575 1450);
DISPLAY INVISIBLE (3575 1450);
FORCEPROP 1 LAST PATH I112
J 0
(3248 1575);
DISPLAY 0.872340 (3248 1575);
PAINT GREEN (3248 1575);
DISPLAY INVISIBLE (3248 1575);
FORCEADD TAP..1
(3250 1675);
FORCEPROP 3 LASTPIN (3200 1675) SIG_NAME M_B_CPU0_SA_CA<6>
J 0
(3210 1685);
DISPLAY 0.659574 (3210 1685);
PAINT MONO (3210 1685);
DISPLAY INVISIBLE (3210 1685);
FORCEPROP 1 LASTPIN (3200 1675) BN 6
J 0
(3188 1683);
DISPLAY 0.680851 (3188 1683);
PAINT GREEN (3188 1683);
FORCEPROP 2 LAST CDS_LIB standard
J 0
(3250 1675);
DISPLAY INVISIBLE (3250 1675);
FORCEPROP 1 LAST BODY_TYPE PLUMBING
J 0
(3250 1725);
DISPLAY 0.872340 (3250 1725);
PAINT GREEN (3250 1725);
DISPLAY INVISIBLE (3250 1725);
FORCEPROP 1 LAST HDL_TAP TRUE
J 0
(3575 1550);
DISPLAY 0.872340 (3575 1550);
DISPLAY INVISIBLE (3575 1550);
FORCEPROP 1 LAST PATH I113
J 0
(3248 1675);
DISPLAY 0.872340 (3248 1675);
PAINT GREEN (3248 1675);
DISPLAY INVISIBLE (3248 1675);
FORCEADD TAP..1
(3250 1625);
FORCEPROP 3 LASTPIN (3200 1625) SIG_NAME M_B_CPU0_SA_CA<5>
J 0
(3210 1635);
DISPLAY 0.659574 (3210 1635);
PAINT MONO (3210 1635);
DISPLAY INVISIBLE (3210 1635);
FORCEPROP 1 LASTPIN (3200 1625) BN 5
J 0
(3188 1633);
DISPLAY 0.680851 (3188 1633);
PAINT GREEN (3188 1633);
FORCEPROP 2 LAST CDS_LIB standard
J 0
(3250 1625);
DISPLAY INVISIBLE (3250 1625);
FORCEPROP 1 LAST BODY_TYPE PLUMBING
J 0
(3250 1675);
DISPLAY 0.872340 (3250 1675);
PAINT GREEN (3250 1675);
DISPLAY INVISIBLE (3250 1675);
FORCEPROP 1 LAST HDL_TAP TRUE
J 0
(3575 1500);
DISPLAY 0.872340 (3575 1500);
DISPLAY INVISIBLE (3575 1500);
FORCEPROP 1 LAST PATH I114
J 0
(3248 1625);
DISPLAY 0.872340 (3248 1625);
PAINT GREEN (3248 1625);
DISPLAY INVISIBLE (3248 1625);
FORCEADD OFFPAGE..4
(4350 -125);
FORCEPROP 2 LAST $XR0 84 
J 0
(4536 -125);
DISPLAY 0.638298 (4536 -125);
PAINT MONO (4536 -125);
FORCEPROP 2 LAST CDS_LIB standard
J 0
(4350 -125);
PAINT MONO (4350 -125);
DISPLAY INVISIBLE (4350 -125);
FORCEPROP 1 LAST OFFPAGE TRUE
J 0
(4675 -250);
DISPLAY 1.170213 (4675 -250);
PAINT GREEN (4675 -250);
DISPLAY INVISIBLE (4675 -250);
FORCEPROP 1 LAST COMMENT_BODY TRUE
J 0
(4325 -225);
DISPLAY 1.170213 (4325 -225);
PAINT GREEN (4325 -225);
DISPLAY INVISIBLE (4325 -225);
FORCEPROP 2 LAST PATH I115
J 0
(4525 -50);
DISPLAY 1.021277 (4525 -50);
DISPLAY INVISIBLE (4525 -50);
FORCEADD OFFPAGE..4
(4350 -75);
FORCEPROP 2 LAST $XR0 85 
J 0
(4536 -75);
DISPLAY 0.638298 (4536 -75);
PAINT MONO (4536 -75);
FORCEPROP 2 LAST CDS_LIB standard
J 0
(4350 -75);
PAINT MONO (4350 -75);
DISPLAY INVISIBLE (4350 -75);
FORCEPROP 1 LAST OFFPAGE TRUE
J 0
(4675 -200);
DISPLAY 1.170213 (4675 -200);
PAINT GREEN (4675 -200);
DISPLAY INVISIBLE (4675 -200);
FORCEPROP 1 LAST COMMENT_BODY TRUE
J 0
(4325 -175);
DISPLAY 1.170213 (4325 -175);
PAINT GREEN (4325 -175);
DISPLAY INVISIBLE (4325 -175);
FORCEPROP 2 LAST PATH I116
J 0
(4525 0);
DISPLAY 1.021277 (4525 0);
DISPLAY INVISIBLE (4525 0);
FORCEADD OFFPAGE..4
(4350 25);
FORCEPROP 2 LAST $XR0 84 
J 0
(4536 25);
DISPLAY 0.638298 (4536 25);
PAINT MONO (4536 25);
FORCEPROP 2 LAST CDS_LIB standard
J 0
(4350 25);
PAINT MONO (4350 25);
DISPLAY INVISIBLE (4350 25);
FORCEPROP 1 LAST OFFPAGE TRUE
J 0
(4675 -100);
DISPLAY 1.170213 (4675 -100);
PAINT GREEN (4675 -100);
DISPLAY INVISIBLE (4675 -100);
FORCEPROP 1 LAST COMMENT_BODY TRUE
J 0
(4325 -75);
DISPLAY 1.170213 (4325 -75);
PAINT GREEN (4325 -75);
DISPLAY INVISIBLE (4325 -75);
FORCEPROP 2 LAST PATH I117
J 0
(4525 100);
DISPLAY 1.021277 (4525 100);
DISPLAY INVISIBLE (4525 100);
FORCEADD OFFPAGE..4
(4350 75);
FORCEPROP 2 LAST $XR0 85 
J 0
(4536 75);
DISPLAY 0.638298 (4536 75);
PAINT MONO (4536 75);
FORCEPROP 2 LAST CDS_LIB standard
J 0
(4350 75);
PAINT MONO (4350 75);
DISPLAY INVISIBLE (4350 75);
FORCEPROP 1 LAST OFFPAGE TRUE
J 0
(4675 -50);
DISPLAY 1.170213 (4675 -50);
PAINT GREEN (4675 -50);
DISPLAY INVISIBLE (4675 -50);
FORCEPROP 1 LAST COMMENT_BODY TRUE
J 0
(4325 -25);
DISPLAY 1.170213 (4325 -25);
PAINT GREEN (4325 -25);
DISPLAY INVISIBLE (4325 -25);
FORCEPROP 2 LAST PATH I118
J 0
(4525 150);
DISPLAY 1.021277 (4525 150);
DISPLAY INVISIBLE (4525 150);
FORCEADD OFFPAGE..2
(4350 400);
FORCEPROP 2 LAST $XR1 85 
J 0
(4629 400);
DISPLAY 0.638298 (4629 400);
PAINT MONO (4629 400);
FORCEPROP 2 LAST $XR0 84 
J 0
(4539 400);
DISPLAY 0.638298 (4539 400);
PAINT MONO (4539 400);
FORCEPROP 2 LAST CDS_LIB standard
J 0
(4350 400);
PAINT MONO (4350 400);
DISPLAY INVISIBLE (4350 400);
FORCEPROP 1 LAST OFFPAGE TRUE
J 0
(4675 275);
DISPLAY 1.170213 (4675 275);
PAINT GREEN (4675 275);
DISPLAY INVISIBLE (4675 275);
FORCEPROP 1 LAST COMMENT_BODY TRUE
J 0
(4305 305);
DISPLAY 1.170213 (4305 305);
PAINT GREEN (4305 305);
DISPLAY INVISIBLE (4305 305);
FORCEPROP 2 LAST PATH I119
J 0
(4525 475);
DISPLAY 1.021277 (4525 475);
DISPLAY INVISIBLE (4525 475);
FORCEADD TAP..1
R 2
(-175 225);
FORCEPROP 3 LASTPIN (-125 225) SIG_NAME M_B_CPU0_SB_CB<4>
J 0
(-115 235);
DISPLAY 0.659574 (-115 235);
PAINT MONO (-115 235);
DISPLAY INVISIBLE (-115 235);
FORCEPROP 1 LASTPIN (-125 225) BN 4
J 2
(-113 233);
DISPLAY 0.680851 (-113 233);
PAINT GREEN (-113 233);
FORCEPROP 2 LAST CDS_LIB standard
J 0
(-175 225);
DISPLAY INVISIBLE (-175 225);
FORCEPROP 1 LAST BODY_TYPE PLUMBING
J 2
(-175 275);
DISPLAY 0.872340 (-175 275);
PAINT GREEN (-175 275);
DISPLAY INVISIBLE (-175 275);
FORCEPROP 1 LAST HDL_TAP TRUE
J 2
(-500 100);
DISPLAY 0.872340 (-500 100);
DISPLAY INVISIBLE (-500 100);
FORCEPROP 1 LAST PATH I12
J 2
(-173 225);
DISPLAY 0.872340 (-173 225);
PAINT GREEN (-173 225);
DISPLAY INVISIBLE (-173 225);
FORCEADD OFFPAGE..2
(4350 700);
FORCEPROP 2 LAST $XR1 85 
J 0
(4629 700);
DISPLAY 0.638298 (4629 700);
PAINT MONO (4629 700);
FORCEPROP 2 LAST $XR0 84 
J 0
(4539 700);
DISPLAY 0.638298 (4539 700);
PAINT MONO (4539 700);
FORCEPROP 2 LAST CDS_LIB standard
J 0
(4350 700);
PAINT MONO (4350 700);
DISPLAY INVISIBLE (4350 700);
FORCEPROP 1 LAST OFFPAGE TRUE
J 0
(4675 575);
DISPLAY 1.170213 (4675 575);
PAINT GREEN (4675 575);
DISPLAY INVISIBLE (4675 575);
FORCEPROP 1 LAST COMMENT_BODY TRUE
J 0
(4305 605);
DISPLAY 1.170213 (4305 605);
PAINT GREEN (4305 605);
DISPLAY INVISIBLE (4305 605);
FORCEPROP 2 LAST PATH I120
J 0
(4525 775);
DISPLAY 1.021277 (4525 775);
DISPLAY INVISIBLE (4525 775);
FORCEADD OFFPAGE..2
(4350 825);
FORCEPROP 2 LAST $XR1 85 
J 0
(4629 825);
DISPLAY 0.638298 (4629 825);
PAINT MONO (4629 825);
FORCEPROP 2 LAST $XR0 84 
J 0
(4539 825);
DISPLAY 0.638298 (4539 825);
PAINT MONO (4539 825);
FORCEPROP 2 LAST CDS_LIB standard
J 0
(4350 825);
PAINT MONO (4350 825);
DISPLAY INVISIBLE (4350 825);
FORCEPROP 1 LAST OFFPAGE TRUE
J 0
(4675 700);
DISPLAY 1.170213 (4675 700);
PAINT GREEN (4675 700);
DISPLAY INVISIBLE (4675 700);
FORCEPROP 1 LAST COMMENT_BODY TRUE
J 0
(4305 730);
DISPLAY 1.170213 (4305 730);
PAINT GREEN (4305 730);
DISPLAY INVISIBLE (4305 730);
FORCEPROP 2 LAST PATH I121
J 0
(4525 900);
DISPLAY 1.021277 (4525 900);
DISPLAY INVISIBLE (4525 900);
FORCEADD OFFPAGE..3
(4350 1200);
FORCEPROP 2 LAST $XR1 85 
J 0
(4654 1200);
DISPLAY 0.638298 (4654 1200);
PAINT MONO (4654 1200);
FORCEPROP 2 LAST $XR0 84 
J 0
(4564 1200);
DISPLAY 0.638298 (4564 1200);
PAINT MONO (4564 1200);
FORCEPROP 2 LAST CDS_LIB standard
J 2
(4350 1200);
DISPLAY INVISIBLE (4350 1200);
FORCEPROP 1 LAST OFFPAGE TRUE
J 0
(4675 1075);
DISPLAY 0.872340 (4675 1075);
DISPLAY INVISIBLE (4675 1075);
FORCEPROP 1 LAST COMMENT_BODY TRUE
J 0
(4300 1100);
DISPLAY 0.872340 (4300 1100);
PAINT GREEN (4300 1100);
DISPLAY INVISIBLE (4300 1100);
FORCEPROP 2 LAST PATH I122
J 0
(4550 1275);
DISPLAY 1.021277 (4550 1275);
DISPLAY INVISIBLE (4550 1275);
FORCEADD OFFPAGE..2
(4350 1325);
FORCEPROP 2 LAST $XR1 85 
J 0
(4629 1325);
DISPLAY 0.638298 (4629 1325);
PAINT MONO (4629 1325);
FORCEPROP 2 LAST $XR0 84 
J 0
(4539 1325);
DISPLAY 0.638298 (4539 1325);
PAINT MONO (4539 1325);
FORCEPROP 2 LAST CDS_LIB standard
J 0
(4350 1325);
PAINT MONO (4350 1325);
DISPLAY INVISIBLE (4350 1325);
FORCEPROP 1 LAST OFFPAGE TRUE
J 0
(4675 1200);
DISPLAY 1.170213 (4675 1200);
PAINT GREEN (4675 1200);
DISPLAY INVISIBLE (4675 1200);
FORCEPROP 1 LAST COMMENT_BODY TRUE
J 0
(4305 1230);
DISPLAY 1.170213 (4305 1230);
PAINT GREEN (4305 1230);
DISPLAY INVISIBLE (4305 1230);
FORCEPROP 2 LAST PATH I123
J 0
(4525 1400);
DISPLAY 1.021277 (4525 1400);
DISPLAY INVISIBLE (4525 1400);
FORCEADD OFFPAGE..3
(4350 1700);
FORCEPROP 2 LAST $XR1 85 
J 0
(4654 1700);
DISPLAY 0.638298 (4654 1700);
PAINT MONO (4654 1700);
FORCEPROP 2 LAST $XR0 84 
J 0
(4564 1700);
DISPLAY 0.638298 (4564 1700);
PAINT MONO (4564 1700);
FORCEPROP 2 LAST CDS_LIB standard
J 2
(4350 1700);
DISPLAY INVISIBLE (4350 1700);
FORCEPROP 1 LAST OFFPAGE TRUE
J 0
(4675 1575);
DISPLAY 0.872340 (4675 1575);
DISPLAY INVISIBLE (4675 1575);
FORCEPROP 1 LAST COMMENT_BODY TRUE
J 0
(4300 1600);
DISPLAY 0.872340 (4300 1600);
PAINT GREEN (4300 1600);
DISPLAY INVISIBLE (4300 1600);
FORCEPROP 2 LAST PATH I124
J 0
(4550 1775);
DISPLAY 1.021277 (4550 1775);
DISPLAY INVISIBLE (4550 1775);
FORCEADD TAP..1
(3250 1825);
FORCEPROP 3 LASTPIN (3200 1825) SIG_NAME M_B_CPU0_SB_DQS_DN<0>
J 0
(3210 1835);
DISPLAY 0.659574 (3210 1835);
PAINT MONO (3210 1835);
DISPLAY INVISIBLE (3210 1835);
FORCEPROP 1 LASTPIN (3200 1825) BN 0
J 0
(3188 1833);
DISPLAY 0.680851 (3188 1833);
PAINT GREEN (3188 1833);
FORCEPROP 2 LAST CDS_LIB standard
J 0
(3250 1825);
DISPLAY INVISIBLE (3250 1825);
FORCEPROP 1 LAST BODY_TYPE PLUMBING
J 0
(3250 1875);
DISPLAY 0.872340 (3250 1875);
PAINT GREEN (3250 1875);
DISPLAY INVISIBLE (3250 1875);
FORCEPROP 1 LAST HDL_TAP TRUE
J 0
(3575 1700);
DISPLAY 0.872340 (3575 1700);
DISPLAY INVISIBLE (3575 1700);
FORCEPROP 1 LAST PATH I125
J 0
(3248 1825);
DISPLAY 0.872340 (3248 1825);
PAINT GREEN (3248 1825);
DISPLAY INVISIBLE (3248 1825);
FORCEADD TAP..1
(3250 1925);
FORCEPROP 3 LASTPIN (3200 1925) SIG_NAME M_B_CPU0_SB_DQS_DN<2>
J 0
(3210 1935);
DISPLAY 0.659574 (3210 1935);
PAINT MONO (3210 1935);
DISPLAY INVISIBLE (3210 1935);
FORCEPROP 1 LASTPIN (3200 1925) BN 2
J 0
(3188 1933);
DISPLAY 0.680851 (3188 1933);
PAINT GREEN (3188 1933);
FORCEPROP 2 LAST CDS_LIB standard
J 0
(3250 1925);
DISPLAY INVISIBLE (3250 1925);
FORCEPROP 1 LAST BODY_TYPE PLUMBING
J 0
(3250 1975);
DISPLAY 0.872340 (3250 1975);
PAINT GREEN (3250 1975);
DISPLAY INVISIBLE (3250 1975);
FORCEPROP 1 LAST HDL_TAP TRUE
J 0
(3575 1800);
DISPLAY 0.872340 (3575 1800);
DISPLAY INVISIBLE (3575 1800);
FORCEPROP 1 LAST PATH I126
J 0
(3248 1925);
DISPLAY 0.872340 (3248 1925);
PAINT GREEN (3248 1925);
DISPLAY INVISIBLE (3248 1925);
FORCEADD TAP..1
(3250 1875);
FORCEPROP 3 LASTPIN (3200 1875) SIG_NAME M_B_CPU0_SB_DQS_DN<1>
J 0
(3210 1885);
DISPLAY 0.659574 (3210 1885);
PAINT MONO (3210 1885);
DISPLAY INVISIBLE (3210 1885);
FORCEPROP 1 LASTPIN (3200 1875) BN 1
J 0
(3188 1883);
DISPLAY 0.680851 (3188 1883);
PAINT GREEN (3188 1883);
FORCEPROP 2 LAST CDS_LIB standard
J 0
(3250 1875);
DISPLAY INVISIBLE (3250 1875);
FORCEPROP 1 LAST BODY_TYPE PLUMBING
J 0
(3250 1925);
DISPLAY 0.872340 (3250 1925);
PAINT GREEN (3250 1925);
DISPLAY INVISIBLE (3250 1925);
FORCEPROP 1 LAST HDL_TAP TRUE
J 0
(3575 1750);
DISPLAY 0.872340 (3575 1750);
DISPLAY INVISIBLE (3575 1750);
FORCEPROP 1 LAST PATH I127
J 0
(3248 1875);
DISPLAY 0.872340 (3248 1875);
PAINT GREEN (3248 1875);
DISPLAY INVISIBLE (3248 1875);
FORCEADD TAP..1
(3250 2025);
FORCEPROP 3 LASTPIN (3200 2025) SIG_NAME M_B_CPU0_SB_DQS_DN<4>
J 0
(3210 2035);
DISPLAY 0.659574 (3210 2035);
PAINT MONO (3210 2035);
DISPLAY INVISIBLE (3210 2035);
FORCEPROP 1 LASTPIN (3200 2025) BN 4
J 0
(3188 2033);
DISPLAY 0.680851 (3188 2033);
PAINT GREEN (3188 2033);
FORCEPROP 2 LAST CDS_LIB standard
J 0
(3250 2025);
DISPLAY INVISIBLE (3250 2025);
FORCEPROP 1 LAST BODY_TYPE PLUMBING
J 0
(3250 2075);
DISPLAY 0.872340 (3250 2075);
PAINT GREEN (3250 2075);
DISPLAY INVISIBLE (3250 2075);
FORCEPROP 1 LAST HDL_TAP TRUE
J 0
(3575 1900);
DISPLAY 0.872340 (3575 1900);
DISPLAY INVISIBLE (3575 1900);
FORCEPROP 1 LAST PATH I128
J 0
(3248 2025);
DISPLAY 0.872340 (3248 2025);
PAINT GREEN (3248 2025);
DISPLAY INVISIBLE (3248 2025);
FORCEADD TAP..1
(3250 2075);
FORCEPROP 3 LASTPIN (3200 2075) SIG_NAME M_B_CPU0_SB_DQS_DN<5>
J 0
(3210 2085);
DISPLAY 0.659574 (3210 2085);
PAINT MONO (3210 2085);
DISPLAY INVISIBLE (3210 2085);
FORCEPROP 1 LASTPIN (3200 2075) BN 5
J 0
(3188 2083);
DISPLAY 0.680851 (3188 2083);
PAINT GREEN (3188 2083);
FORCEPROP 2 LAST CDS_LIB standard
J 0
(3250 2075);
DISPLAY INVISIBLE (3250 2075);
FORCEPROP 1 LAST BODY_TYPE PLUMBING
J 0
(3250 2125);
DISPLAY 0.872340 (3250 2125);
PAINT GREEN (3250 2125);
DISPLAY INVISIBLE (3250 2125);
FORCEPROP 1 LAST HDL_TAP TRUE
J 0
(3575 1950);
DISPLAY 0.872340 (3575 1950);
DISPLAY INVISIBLE (3575 1950);
FORCEPROP 1 LAST PATH I129
J 0
(3248 2075);
DISPLAY 0.872340 (3248 2075);
PAINT GREEN (3248 2075);
DISPLAY INVISIBLE (3248 2075);
FORCEADD TAP..1
R 2
(-175 175);
FORCEPROP 3 LASTPIN (-125 175) SIG_NAME M_B_CPU0_SB_CB<3>
J 0
(-115 185);
DISPLAY 0.659574 (-115 185);
PAINT MONO (-115 185);
DISPLAY INVISIBLE (-115 185);
FORCEPROP 1 LASTPIN (-125 175) BN 3
J 2
(-113 183);
DISPLAY 0.680851 (-113 183);
PAINT GREEN (-113 183);
FORCEPROP 2 LAST CDS_LIB standard
J 0
(-175 175);
DISPLAY INVISIBLE (-175 175);
FORCEPROP 1 LAST BODY_TYPE PLUMBING
J 2
(-175 225);
DISPLAY 0.872340 (-175 225);
PAINT GREEN (-175 225);
DISPLAY INVISIBLE (-175 225);
FORCEPROP 1 LAST HDL_TAP TRUE
J 2
(-500 50);
DISPLAY 0.872340 (-500 50);
DISPLAY INVISIBLE (-500 50);
FORCEPROP 1 LAST PATH I13
J 2
(-173 175);
DISPLAY 0.872340 (-173 175);
PAINT GREEN (-173 175);
DISPLAY INVISIBLE (-173 175);
FORCEADD TAP..1
(3250 1975);
FORCEPROP 3 LASTPIN (3200 1975) SIG_NAME M_B_CPU0_SB_DQS_DN<3>
J 0
(3210 1985);
DISPLAY 0.659574 (3210 1985);
PAINT MONO (3210 1985);
DISPLAY INVISIBLE (3210 1985);
FORCEPROP 1 LASTPIN (3200 1975) BN 3
J 0
(3188 1983);
DISPLAY 0.680851 (3188 1983);
PAINT GREEN (3188 1983);
FORCEPROP 2 LAST CDS_LIB standard
J 0
(3250 1975);
DISPLAY INVISIBLE (3250 1975);
FORCEPROP 1 LAST BODY_TYPE PLUMBING
J 0
(3250 2025);
DISPLAY 0.872340 (3250 2025);
PAINT GREEN (3250 2025);
DISPLAY INVISIBLE (3250 2025);
FORCEPROP 1 LAST HDL_TAP TRUE
J 0
(3575 1850);
DISPLAY 0.872340 (3575 1850);
DISPLAY INVISIBLE (3575 1850);
FORCEPROP 1 LAST PATH I130
J 0
(3248 1975);
DISPLAY 0.872340 (3248 1975);
PAINT GREEN (3248 1975);
DISPLAY INVISIBLE (3248 1975);
FORCEADD TAP..1
(3250 2125);
FORCEPROP 3 LASTPIN (3200 2125) SIG_NAME M_B_CPU0_SB_DQS_DN<6>
J 0
(3210 2135);
DISPLAY 0.659574 (3210 2135);
PAINT MONO (3210 2135);
DISPLAY INVISIBLE (3210 2135);
FORCEPROP 1 LASTPIN (3200 2125) BN 6
J 0
(3188 2133);
DISPLAY 0.680851 (3188 2133);
PAINT GREEN (3188 2133);
FORCEPROP 2 LAST CDS_LIB standard
J 0
(3250 2125);
DISPLAY INVISIBLE (3250 2125);
FORCEPROP 1 LAST BODY_TYPE PLUMBING
J 0
(3250 2175);
DISPLAY 0.872340 (3250 2175);
PAINT GREEN (3250 2175);
DISPLAY INVISIBLE (3250 2175);
FORCEPROP 1 LAST HDL_TAP TRUE
J 0
(3575 2000);
DISPLAY 0.872340 (3575 2000);
DISPLAY INVISIBLE (3575 2000);
FORCEPROP 1 LAST PATH I131
J 0
(3248 2125);
DISPLAY 0.872340 (3248 2125);
PAINT GREEN (3248 2125);
DISPLAY INVISIBLE (3248 2125);
FORCEADD TAP..1
(3250 2175);
FORCEPROP 3 LASTPIN (3200 2175) SIG_NAME M_B_CPU0_SB_DQS_DN<7>
J 0
(3210 2185);
DISPLAY 0.659574 (3210 2185);
PAINT MONO (3210 2185);
DISPLAY INVISIBLE (3210 2185);
FORCEPROP 1 LASTPIN (3200 2175) BN 7
J 0
(3188 2183);
DISPLAY 0.680851 (3188 2183);
PAINT GREEN (3188 2183);
FORCEPROP 2 LAST CDS_LIB standard
J 0
(3250 2175);
DISPLAY INVISIBLE (3250 2175);
FORCEPROP 1 LAST BODY_TYPE PLUMBING
J 0
(3250 2225);
DISPLAY 0.872340 (3250 2225);
PAINT GREEN (3250 2225);
DISPLAY INVISIBLE (3250 2225);
FORCEPROP 1 LAST HDL_TAP TRUE
J 0
(3575 2050);
DISPLAY 0.872340 (3575 2050);
DISPLAY INVISIBLE (3575 2050);
FORCEPROP 1 LAST PATH I132
J 0
(3248 2175);
DISPLAY 0.872340 (3248 2175);
PAINT GREEN (3248 2175);
DISPLAY INVISIBLE (3248 2175);
FORCEADD TAP..1
(3250 2275);
FORCEPROP 3 LASTPIN (3200 2275) SIG_NAME M_B_CPU0_SB_DQS_DN<9>
J 0
(3210 2285);
DISPLAY 0.659574 (3210 2285);
PAINT MONO (3210 2285);
DISPLAY INVISIBLE (3210 2285);
FORCEPROP 1 LASTPIN (3200 2275) BN 9
J 0
(3188 2283);
DISPLAY 0.680851 (3188 2283);
PAINT GREEN (3188 2283);
FORCEPROP 2 LAST CDS_LIB standard
J 0
(3250 2275);
DISPLAY INVISIBLE (3250 2275);
FORCEPROP 1 LAST BODY_TYPE PLUMBING
J 0
(3250 2325);
DISPLAY 0.872340 (3250 2325);
PAINT GREEN (3250 2325);
DISPLAY INVISIBLE (3250 2325);
FORCEPROP 1 LAST HDL_TAP TRUE
J 0
(3575 2150);
DISPLAY 0.872340 (3575 2150);
DISPLAY INVISIBLE (3575 2150);
FORCEPROP 1 LAST PATH I133
J 0
(3248 2275);
DISPLAY 0.872340 (3248 2275);
PAINT GREEN (3248 2275);
DISPLAY INVISIBLE (3248 2275);
FORCEADD TAP..1
(3250 2225);
FORCEPROP 3 LASTPIN (3200 2225) SIG_NAME M_B_CPU0_SB_DQS_DN<8>
J 0
(3210 2235);
DISPLAY 0.659574 (3210 2235);
PAINT MONO (3210 2235);
DISPLAY INVISIBLE (3210 2235);
FORCEPROP 1 LASTPIN (3200 2225) BN 8
J 0
(3188 2233);
DISPLAY 0.680851 (3188 2233);
PAINT GREEN (3188 2233);
FORCEPROP 2 LAST CDS_LIB standard
J 0
(3250 2225);
DISPLAY INVISIBLE (3250 2225);
FORCEPROP 1 LAST BODY_TYPE PLUMBING
J 0
(3250 2275);
DISPLAY 0.872340 (3250 2275);
PAINT GREEN (3250 2275);
DISPLAY INVISIBLE (3250 2275);
FORCEPROP 1 LAST HDL_TAP TRUE
J 0
(3575 2100);
DISPLAY 0.872340 (3575 2100);
DISPLAY INVISIBLE (3575 2100);
FORCEPROP 1 LAST PATH I134
J 0
(3248 2225);
DISPLAY 0.872340 (3248 2225);
PAINT GREEN (3248 2225);
DISPLAY INVISIBLE (3248 2225);
FORCEADD TAP..1
(3250 2375);
FORCEPROP 3 LASTPIN (3200 2375) SIG_NAME M_B_CPU0_SB_DQS_DP<0>
J 0
(3210 2385);
DISPLAY 0.659574 (3210 2385);
PAINT MONO (3210 2385);
DISPLAY INVISIBLE (3210 2385);
FORCEPROP 1 LASTPIN (3200 2375) BN 0
J 0
(3188 2383);
DISPLAY 0.680851 (3188 2383);
PAINT GREEN (3188 2383);
FORCEPROP 2 LAST CDS_LIB standard
J 0
(3250 2375);
DISPLAY INVISIBLE (3250 2375);
FORCEPROP 1 LAST BODY_TYPE PLUMBING
J 0
(3250 2425);
DISPLAY 0.872340 (3250 2425);
PAINT GREEN (3250 2425);
DISPLAY INVISIBLE (3250 2425);
FORCEPROP 1 LAST HDL_TAP TRUE
J 0
(3575 2250);
DISPLAY 0.872340 (3575 2250);
DISPLAY INVISIBLE (3575 2250);
FORCEPROP 1 LAST PATH I135
J 0
(3248 2375);
DISPLAY 0.872340 (3248 2375);
PAINT GREEN (3248 2375);
DISPLAY INVISIBLE (3248 2375);
FORCEADD TAP..1
(3250 2425);
FORCEPROP 3 LASTPIN (3200 2425) SIG_NAME M_B_CPU0_SB_DQS_DP<1>
J 0
(3210 2435);
DISPLAY 0.659574 (3210 2435);
PAINT MONO (3210 2435);
DISPLAY INVISIBLE (3210 2435);
FORCEPROP 1 LASTPIN (3200 2425) BN 1
J 0
(3188 2433);
DISPLAY 0.680851 (3188 2433);
PAINT GREEN (3188 2433);
FORCEPROP 2 LAST CDS_LIB standard
J 0
(3250 2425);
DISPLAY INVISIBLE (3250 2425);
FORCEPROP 1 LAST BODY_TYPE PLUMBING
J 0
(3250 2475);
DISPLAY 0.872340 (3250 2475);
PAINT GREEN (3250 2475);
DISPLAY INVISIBLE (3250 2475);
FORCEPROP 1 LAST HDL_TAP TRUE
J 0
(3575 2300);
DISPLAY 0.872340 (3575 2300);
DISPLAY INVISIBLE (3575 2300);
FORCEPROP 1 LAST PATH I136
J 0
(3248 2425);
DISPLAY 0.872340 (3248 2425);
PAINT GREEN (3248 2425);
DISPLAY INVISIBLE (3248 2425);
FORCEADD TAP..1
(3250 2575);
FORCEPROP 3 LASTPIN (3200 2575) SIG_NAME M_B_CPU0_SB_DQS_DP<4>
J 0
(3210 2585);
DISPLAY 0.659574 (3210 2585);
PAINT MONO (3210 2585);
DISPLAY INVISIBLE (3210 2585);
FORCEPROP 1 LASTPIN (3200 2575) BN 4
J 0
(3188 2583);
DISPLAY 0.680851 (3188 2583);
PAINT GREEN (3188 2583);
FORCEPROP 2 LAST CDS_LIB standard
J 0
(3250 2575);
DISPLAY INVISIBLE (3250 2575);
FORCEPROP 1 LAST BODY_TYPE PLUMBING
J 0
(3250 2625);
DISPLAY 0.872340 (3250 2625);
PAINT GREEN (3250 2625);
DISPLAY INVISIBLE (3250 2625);
FORCEPROP 1 LAST HDL_TAP TRUE
J 0
(3575 2450);
DISPLAY 0.872340 (3575 2450);
DISPLAY INVISIBLE (3575 2450);
FORCEPROP 1 LAST PATH I137
J 0
(3248 2575);
DISPLAY 0.872340 (3248 2575);
PAINT GREEN (3248 2575);
DISPLAY INVISIBLE (3248 2575);
FORCEADD TAP..1
(3250 2475);
FORCEPROP 3 LASTPIN (3200 2475) SIG_NAME M_B_CPU0_SB_DQS_DP<2>
J 0
(3210 2485);
DISPLAY 0.659574 (3210 2485);
PAINT MONO (3210 2485);
DISPLAY INVISIBLE (3210 2485);
FORCEPROP 1 LASTPIN (3200 2475) BN 2
J 0
(3188 2483);
DISPLAY 0.680851 (3188 2483);
PAINT GREEN (3188 2483);
FORCEPROP 2 LAST CDS_LIB standard
J 0
(3250 2475);
DISPLAY INVISIBLE (3250 2475);
FORCEPROP 1 LAST BODY_TYPE PLUMBING
J 0
(3250 2525);
DISPLAY 0.872340 (3250 2525);
PAINT GREEN (3250 2525);
DISPLAY INVISIBLE (3250 2525);
FORCEPROP 1 LAST HDL_TAP TRUE
J 0
(3575 2350);
DISPLAY 0.872340 (3575 2350);
DISPLAY INVISIBLE (3575 2350);
FORCEPROP 1 LAST PATH I138
J 0
(3248 2475);
DISPLAY 0.872340 (3248 2475);
PAINT GREEN (3248 2475);
DISPLAY INVISIBLE (3248 2475);
FORCEADD TAP..1
(3250 2525);
FORCEPROP 3 LASTPIN (3200 2525) SIG_NAME M_B_CPU0_SB_DQS_DP<3>
J 0
(3210 2535);
DISPLAY 0.659574 (3210 2535);
PAINT MONO (3210 2535);
DISPLAY INVISIBLE (3210 2535);
FORCEPROP 1 LASTPIN (3200 2525) BN 3
J 0
(3188 2533);
DISPLAY 0.680851 (3188 2533);
PAINT GREEN (3188 2533);
FORCEPROP 2 LAST CDS_LIB standard
J 0
(3250 2525);
DISPLAY INVISIBLE (3250 2525);
FORCEPROP 1 LAST BODY_TYPE PLUMBING
J 0
(3250 2575);
DISPLAY 0.872340 (3250 2575);
PAINT GREEN (3250 2575);
DISPLAY INVISIBLE (3250 2575);
FORCEPROP 1 LAST HDL_TAP TRUE
J 0
(3575 2400);
DISPLAY 0.872340 (3575 2400);
DISPLAY INVISIBLE (3575 2400);
FORCEPROP 1 LAST PATH I139
J 0
(3248 2525);
DISPLAY 0.872340 (3248 2525);
PAINT GREEN (3248 2525);
DISPLAY INVISIBLE (3248 2525);
FORCEADD TAP..1
R 2
(-175 275);
FORCEPROP 3 LASTPIN (-125 275) SIG_NAME M_B_CPU0_SB_CB<5>
J 0
(-115 285);
DISPLAY 0.659574 (-115 285);
PAINT MONO (-115 285);
DISPLAY INVISIBLE (-115 285);
FORCEPROP 1 LASTPIN (-125 275) BN 5
J 2
(-113 283);
DISPLAY 0.680851 (-113 283);
PAINT GREEN (-113 283);
FORCEPROP 2 LAST CDS_LIB standard
J 0
(-175 275);
DISPLAY INVISIBLE (-175 275);
FORCEPROP 1 LAST BODY_TYPE PLUMBING
J 2
(-175 325);
DISPLAY 0.872340 (-175 325);
PAINT GREEN (-175 325);
DISPLAY INVISIBLE (-175 325);
FORCEPROP 1 LAST HDL_TAP TRUE
J 2
(-500 150);
DISPLAY 0.872340 (-500 150);
DISPLAY INVISIBLE (-500 150);
FORCEPROP 1 LAST PATH I14
J 2
(-173 275);
DISPLAY 0.872340 (-173 275);
PAINT GREEN (-173 275);
DISPLAY INVISIBLE (-173 275);
FORCEADD TAP..1
(3250 2675);
FORCEPROP 3 LASTPIN (3200 2675) SIG_NAME M_B_CPU0_SB_DQS_DP<6>
J 0
(3210 2685);
DISPLAY 0.659574 (3210 2685);
PAINT MONO (3210 2685);
DISPLAY INVISIBLE (3210 2685);
FORCEPROP 1 LASTPIN (3200 2675) BN 6
J 0
(3188 2683);
DISPLAY 0.680851 (3188 2683);
PAINT GREEN (3188 2683);
FORCEPROP 2 LAST CDS_LIB standard
J 0
(3250 2675);
DISPLAY INVISIBLE (3250 2675);
FORCEPROP 1 LAST BODY_TYPE PLUMBING
J 0
(3250 2725);
DISPLAY 0.872340 (3250 2725);
PAINT GREEN (3250 2725);
DISPLAY INVISIBLE (3250 2725);
FORCEPROP 1 LAST HDL_TAP TRUE
J 0
(3575 2550);
DISPLAY 0.872340 (3575 2550);
DISPLAY INVISIBLE (3575 2550);
FORCEPROP 1 LAST PATH I140
J 0
(3248 2675);
DISPLAY 0.872340 (3248 2675);
PAINT GREEN (3248 2675);
DISPLAY INVISIBLE (3248 2675);
FORCEADD TAP..1
(3250 2625);
FORCEPROP 3 LASTPIN (3200 2625) SIG_NAME M_B_CPU0_SB_DQS_DP<5>
J 0
(3210 2635);
DISPLAY 0.659574 (3210 2635);
PAINT MONO (3210 2635);
DISPLAY INVISIBLE (3210 2635);
FORCEPROP 1 LASTPIN (3200 2625) BN 5
J 0
(3188 2633);
DISPLAY 0.680851 (3188 2633);
PAINT GREEN (3188 2633);
FORCEPROP 2 LAST CDS_LIB standard
J 0
(3250 2625);
DISPLAY INVISIBLE (3250 2625);
FORCEPROP 1 LAST BODY_TYPE PLUMBING
J 0
(3250 2675);
DISPLAY 0.872340 (3250 2675);
PAINT GREEN (3250 2675);
DISPLAY INVISIBLE (3250 2675);
FORCEPROP 1 LAST HDL_TAP TRUE
J 0
(3575 2500);
DISPLAY 0.872340 (3575 2500);
DISPLAY INVISIBLE (3575 2500);
FORCEPROP 1 LAST PATH I141
J 0
(3248 2625);
DISPLAY 0.872340 (3248 2625);
PAINT GREEN (3248 2625);
DISPLAY INVISIBLE (3248 2625);
FORCEADD TAP..1
(3250 2775);
FORCEPROP 3 LASTPIN (3200 2775) SIG_NAME M_B_CPU0_SB_DQS_DP<8>
J 0
(3210 2785);
DISPLAY 0.659574 (3210 2785);
PAINT MONO (3210 2785);
DISPLAY INVISIBLE (3210 2785);
FORCEPROP 1 LASTPIN (3200 2775) BN 8
J 0
(3188 2783);
DISPLAY 0.680851 (3188 2783);
PAINT GREEN (3188 2783);
FORCEPROP 2 LAST CDS_LIB standard
J 0
(3250 2775);
DISPLAY INVISIBLE (3250 2775);
FORCEPROP 1 LAST BODY_TYPE PLUMBING
J 0
(3250 2825);
DISPLAY 0.872340 (3250 2825);
PAINT GREEN (3250 2825);
DISPLAY INVISIBLE (3250 2825);
FORCEPROP 1 LAST HDL_TAP TRUE
J 0
(3575 2650);
DISPLAY 0.872340 (3575 2650);
DISPLAY INVISIBLE (3575 2650);
FORCEPROP 1 LAST PATH I142
J 0
(3248 2775);
DISPLAY 0.872340 (3248 2775);
PAINT GREEN (3248 2775);
DISPLAY INVISIBLE (3248 2775);
FORCEADD TAP..1
(3250 2825);
FORCEPROP 3 LASTPIN (3200 2825) SIG_NAME M_B_CPU0_SB_DQS_DP<9>
J 0
(3210 2835);
DISPLAY 0.659574 (3210 2835);
PAINT MONO (3210 2835);
DISPLAY INVISIBLE (3210 2835);
FORCEPROP 1 LASTPIN (3200 2825) BN 9
J 0
(3188 2833);
DISPLAY 0.680851 (3188 2833);
PAINT GREEN (3188 2833);
FORCEPROP 2 LAST CDS_LIB standard
J 0
(3250 2825);
DISPLAY INVISIBLE (3250 2825);
FORCEPROP 1 LAST BODY_TYPE PLUMBING
J 0
(3250 2875);
DISPLAY 0.872340 (3250 2875);
PAINT GREEN (3250 2875);
DISPLAY INVISIBLE (3250 2875);
FORCEPROP 1 LAST HDL_TAP TRUE
J 0
(3575 2700);
DISPLAY 0.872340 (3575 2700);
DISPLAY INVISIBLE (3575 2700);
FORCEPROP 1 LAST PATH I143
J 0
(3248 2825);
DISPLAY 0.872340 (3248 2825);
PAINT GREEN (3248 2825);
DISPLAY INVISIBLE (3248 2825);
FORCEADD TAP..1
(3250 2725);
FORCEPROP 3 LASTPIN (3200 2725) SIG_NAME M_B_CPU0_SB_DQS_DP<7>
J 0
(3210 2735);
DISPLAY 0.659574 (3210 2735);
PAINT MONO (3210 2735);
DISPLAY INVISIBLE (3210 2735);
FORCEPROP 1 LASTPIN (3200 2725) BN 7
J 0
(3188 2733);
DISPLAY 0.680851 (3188 2733);
PAINT GREEN (3188 2733);
FORCEPROP 2 LAST CDS_LIB standard
J 0
(3250 2725);
DISPLAY INVISIBLE (3250 2725);
FORCEPROP 1 LAST BODY_TYPE PLUMBING
J 0
(3250 2775);
DISPLAY 0.872340 (3250 2775);
PAINT GREEN (3250 2775);
DISPLAY INVISIBLE (3250 2775);
FORCEPROP 1 LAST HDL_TAP TRUE
J 0
(3575 2600);
DISPLAY 0.872340 (3575 2600);
DISPLAY INVISIBLE (3575 2600);
FORCEPROP 1 LAST PATH I144
J 0
(3248 2725);
DISPLAY 0.872340 (3248 2725);
PAINT GREEN (3248 2725);
DISPLAY INVISIBLE (3248 2725);
FORCEADD TAP..1
(3250 2975);
FORCEPROP 3 LASTPIN (3200 2975) SIG_NAME M_B_CPU0_SA_DQS_DN<0>
J 0
(3210 2985);
DISPLAY 0.659574 (3210 2985);
PAINT MONO (3210 2985);
DISPLAY INVISIBLE (3210 2985);
FORCEPROP 1 LASTPIN (3200 2975) BN 0
J 0
(3188 2983);
DISPLAY 0.680851 (3188 2983);
PAINT GREEN (3188 2983);
FORCEPROP 2 LAST CDS_LIB standard
J 0
(3250 2975);
DISPLAY INVISIBLE (3250 2975);
FORCEPROP 1 LAST BODY_TYPE PLUMBING
J 0
(3250 3025);
DISPLAY 0.872340 (3250 3025);
PAINT GREEN (3250 3025);
DISPLAY INVISIBLE (3250 3025);
FORCEPROP 1 LAST HDL_TAP TRUE
J 0
(3575 2850);
DISPLAY 0.872340 (3575 2850);
DISPLAY INVISIBLE (3575 2850);
FORCEPROP 1 LAST PATH I145
J 0
(3248 2975);
DISPLAY 0.872340 (3248 2975);
PAINT GREEN (3248 2975);
DISPLAY INVISIBLE (3248 2975);
FORCEADD TAP..1
(3250 3075);
FORCEPROP 3 LASTPIN (3200 3075) SIG_NAME M_B_CPU0_SA_DQS_DN<2>
J 0
(3210 3085);
DISPLAY 0.659574 (3210 3085);
PAINT MONO (3210 3085);
DISPLAY INVISIBLE (3210 3085);
FORCEPROP 1 LASTPIN (3200 3075) BN 2
J 0
(3188 3083);
DISPLAY 0.680851 (3188 3083);
PAINT GREEN (3188 3083);
FORCEPROP 2 LAST CDS_LIB standard
J 0
(3250 3075);
DISPLAY INVISIBLE (3250 3075);
FORCEPROP 1 LAST BODY_TYPE PLUMBING
J 0
(3250 3125);
DISPLAY 0.872340 (3250 3125);
PAINT GREEN (3250 3125);
DISPLAY INVISIBLE (3250 3125);
FORCEPROP 1 LAST HDL_TAP TRUE
J 0
(3575 2950);
DISPLAY 0.872340 (3575 2950);
DISPLAY INVISIBLE (3575 2950);
FORCEPROP 1 LAST PATH I146
J 0
(3248 3075);
DISPLAY 0.872340 (3248 3075);
PAINT GREEN (3248 3075);
DISPLAY INVISIBLE (3248 3075);
FORCEADD TAP..1
(3250 3025);
FORCEPROP 3 LASTPIN (3200 3025) SIG_NAME M_B_CPU0_SA_DQS_DN<1>
J 0
(3210 3035);
DISPLAY 0.659574 (3210 3035);
PAINT MONO (3210 3035);
DISPLAY INVISIBLE (3210 3035);
FORCEPROP 1 LASTPIN (3200 3025) BN 1
J 0
(3188 3033);
DISPLAY 0.680851 (3188 3033);
PAINT GREEN (3188 3033);
FORCEPROP 2 LAST CDS_LIB standard
J 0
(3250 3025);
DISPLAY INVISIBLE (3250 3025);
FORCEPROP 1 LAST BODY_TYPE PLUMBING
J 0
(3250 3075);
DISPLAY 0.872340 (3250 3075);
PAINT GREEN (3250 3075);
DISPLAY INVISIBLE (3250 3075);
FORCEPROP 1 LAST HDL_TAP TRUE
J 0
(3575 2900);
DISPLAY 0.872340 (3575 2900);
DISPLAY INVISIBLE (3575 2900);
FORCEPROP 1 LAST PATH I147
J 0
(3248 3025);
DISPLAY 0.872340 (3248 3025);
PAINT GREEN (3248 3025);
DISPLAY INVISIBLE (3248 3025);
FORCEADD TAP..1
(3250 3175);
FORCEPROP 3 LASTPIN (3200 3175) SIG_NAME M_B_CPU0_SA_DQS_DN<4>
J 0
(3210 3185);
DISPLAY 0.659574 (3210 3185);
PAINT MONO (3210 3185);
DISPLAY INVISIBLE (3210 3185);
FORCEPROP 1 LASTPIN (3200 3175) BN 4
J 0
(3188 3183);
DISPLAY 0.680851 (3188 3183);
PAINT GREEN (3188 3183);
FORCEPROP 2 LAST CDS_LIB standard
J 0
(3250 3175);
DISPLAY INVISIBLE (3250 3175);
FORCEPROP 1 LAST BODY_TYPE PLUMBING
J 0
(3250 3225);
DISPLAY 0.872340 (3250 3225);
PAINT GREEN (3250 3225);
DISPLAY INVISIBLE (3250 3225);
FORCEPROP 1 LAST HDL_TAP TRUE
J 0
(3575 3050);
DISPLAY 0.872340 (3575 3050);
DISPLAY INVISIBLE (3575 3050);
FORCEPROP 1 LAST PATH I148
J 0
(3248 3175);
DISPLAY 0.872340 (3248 3175);
PAINT GREEN (3248 3175);
DISPLAY INVISIBLE (3248 3175);
FORCEADD TAP..1
(3250 3225);
FORCEPROP 3 LASTPIN (3200 3225) SIG_NAME M_B_CPU0_SA_DQS_DN<5>
J 0
(3210 3235);
DISPLAY 0.659574 (3210 3235);
PAINT MONO (3210 3235);
DISPLAY INVISIBLE (3210 3235);
FORCEPROP 1 LASTPIN (3200 3225) BN 5
J 0
(3188 3233);
DISPLAY 0.680851 (3188 3233);
PAINT GREEN (3188 3233);
FORCEPROP 2 LAST CDS_LIB standard
J 0
(3250 3225);
DISPLAY INVISIBLE (3250 3225);
FORCEPROP 1 LAST BODY_TYPE PLUMBING
J 0
(3250 3275);
DISPLAY 0.872340 (3250 3275);
PAINT GREEN (3250 3275);
DISPLAY INVISIBLE (3250 3275);
FORCEPROP 1 LAST HDL_TAP TRUE
J 0
(3575 3100);
DISPLAY 0.872340 (3575 3100);
DISPLAY INVISIBLE (3575 3100);
FORCEPROP 1 LAST PATH I149
J 0
(3248 3225);
DISPLAY 0.872340 (3248 3225);
PAINT GREEN (3248 3225);
DISPLAY INVISIBLE (3248 3225);
FORCEADD TAP..1
R 2
(-175 475);
FORCEPROP 3 LASTPIN (-125 475) SIG_NAME M_B_CPU0_SB_DQ<1>
J 0
(-115 485);
DISPLAY 0.659574 (-115 485);
PAINT MONO (-115 485);
DISPLAY INVISIBLE (-115 485);
FORCEPROP 1 LASTPIN (-125 475) BN 1
J 2
(-113 483);
DISPLAY 0.680851 (-113 483);
PAINT GREEN (-113 483);
FORCEPROP 2 LAST CDS_LIB standard
J 0
(-175 475);
DISPLAY INVISIBLE (-175 475);
FORCEPROP 1 LAST BODY_TYPE PLUMBING
J 2
(-175 525);
DISPLAY 0.872340 (-175 525);
PAINT GREEN (-175 525);
DISPLAY INVISIBLE (-175 525);
FORCEPROP 1 LAST HDL_TAP TRUE
J 2
(-500 350);
DISPLAY 0.872340 (-500 350);
DISPLAY INVISIBLE (-500 350);
FORCEPROP 1 LAST PATH I15
J 2
(-173 475);
DISPLAY 0.872340 (-173 475);
PAINT GREEN (-173 475);
DISPLAY INVISIBLE (-173 475);
FORCEADD TAP..1
(3250 3125);
FORCEPROP 3 LASTPIN (3200 3125) SIG_NAME M_B_CPU0_SA_DQS_DN<3>
J 0
(3210 3135);
DISPLAY 0.659574 (3210 3135);
PAINT MONO (3210 3135);
DISPLAY INVISIBLE (3210 3135);
FORCEPROP 1 LASTPIN (3200 3125) BN 3
J 0
(3188 3133);
DISPLAY 0.680851 (3188 3133);
PAINT GREEN (3188 3133);
FORCEPROP 2 LAST CDS_LIB standard
J 0
(3250 3125);
DISPLAY INVISIBLE (3250 3125);
FORCEPROP 1 LAST BODY_TYPE PLUMBING
J 0
(3250 3175);
DISPLAY 0.872340 (3250 3175);
PAINT GREEN (3250 3175);
DISPLAY INVISIBLE (3250 3175);
FORCEPROP 1 LAST HDL_TAP TRUE
J 0
(3575 3000);
DISPLAY 0.872340 (3575 3000);
DISPLAY INVISIBLE (3575 3000);
FORCEPROP 1 LAST PATH I150
J 0
(3248 3125);
DISPLAY 0.872340 (3248 3125);
PAINT GREEN (3248 3125);
DISPLAY INVISIBLE (3248 3125);
FORCEADD TAP..1
(3250 3275);
FORCEPROP 3 LASTPIN (3200 3275) SIG_NAME M_B_CPU0_SA_DQS_DN<6>
J 0
(3210 3285);
DISPLAY 0.659574 (3210 3285);
PAINT MONO (3210 3285);
DISPLAY INVISIBLE (3210 3285);
FORCEPROP 1 LASTPIN (3200 3275) BN 6
J 0
(3188 3283);
DISPLAY 0.680851 (3188 3283);
PAINT GREEN (3188 3283);
FORCEPROP 2 LAST CDS_LIB standard
J 0
(3250 3275);
DISPLAY INVISIBLE (3250 3275);
FORCEPROP 1 LAST BODY_TYPE PLUMBING
J 0
(3250 3325);
DISPLAY 0.872340 (3250 3325);
PAINT GREEN (3250 3325);
DISPLAY INVISIBLE (3250 3325);
FORCEPROP 1 LAST HDL_TAP TRUE
J 0
(3575 3150);
DISPLAY 0.872340 (3575 3150);
DISPLAY INVISIBLE (3575 3150);
FORCEPROP 1 LAST PATH I151
J 0
(3248 3275);
DISPLAY 0.872340 (3248 3275);
PAINT GREEN (3248 3275);
DISPLAY INVISIBLE (3248 3275);
FORCEADD TAP..1
(3250 3325);
FORCEPROP 3 LASTPIN (3200 3325) SIG_NAME M_B_CPU0_SA_DQS_DN<7>
J 0
(3210 3335);
DISPLAY 0.659574 (3210 3335);
PAINT MONO (3210 3335);
DISPLAY INVISIBLE (3210 3335);
FORCEPROP 1 LASTPIN (3200 3325) BN 7
J 0
(3188 3333);
DISPLAY 0.680851 (3188 3333);
PAINT GREEN (3188 3333);
FORCEPROP 2 LAST CDS_LIB standard
J 0
(3250 3325);
DISPLAY INVISIBLE (3250 3325);
FORCEPROP 1 LAST BODY_TYPE PLUMBING
J 0
(3250 3375);
DISPLAY 0.872340 (3250 3375);
PAINT GREEN (3250 3375);
DISPLAY INVISIBLE (3250 3375);
FORCEPROP 1 LAST HDL_TAP TRUE
J 0
(3575 3200);
DISPLAY 0.872340 (3575 3200);
DISPLAY INVISIBLE (3575 3200);
FORCEPROP 1 LAST PATH I152
J 0
(3248 3325);
DISPLAY 0.872340 (3248 3325);
PAINT GREEN (3248 3325);
DISPLAY INVISIBLE (3248 3325);
FORCEADD TAP..1
(3250 3425);
FORCEPROP 3 LASTPIN (3200 3425) SIG_NAME M_B_CPU0_SA_DQS_DN<9>
J 0
(3210 3435);
DISPLAY 0.659574 (3210 3435);
PAINT MONO (3210 3435);
DISPLAY INVISIBLE (3210 3435);
FORCEPROP 1 LASTPIN (3200 3425) BN 9
J 0
(3188 3433);
DISPLAY 0.680851 (3188 3433);
PAINT GREEN (3188 3433);
FORCEPROP 2 LAST CDS_LIB standard
J 0
(3250 3425);
DISPLAY INVISIBLE (3250 3425);
FORCEPROP 1 LAST BODY_TYPE PLUMBING
J 0
(3250 3475);
DISPLAY 0.872340 (3250 3475);
PAINT GREEN (3250 3475);
DISPLAY INVISIBLE (3250 3475);
FORCEPROP 1 LAST HDL_TAP TRUE
J 0
(3575 3300);
DISPLAY 0.872340 (3575 3300);
DISPLAY INVISIBLE (3575 3300);
FORCEPROP 1 LAST PATH I153
J 0
(3248 3425);
DISPLAY 0.872340 (3248 3425);
PAINT GREEN (3248 3425);
DISPLAY INVISIBLE (3248 3425);
FORCEADD TAP..1
(3250 3375);
FORCEPROP 3 LASTPIN (3200 3375) SIG_NAME M_B_CPU0_SA_DQS_DN<8>
J 0
(3210 3385);
DISPLAY 0.659574 (3210 3385);
PAINT MONO (3210 3385);
DISPLAY INVISIBLE (3210 3385);
FORCEPROP 1 LASTPIN (3200 3375) BN 8
J 0
(3188 3383);
DISPLAY 0.680851 (3188 3383);
PAINT GREEN (3188 3383);
FORCEPROP 2 LAST CDS_LIB standard
J 0
(3250 3375);
DISPLAY INVISIBLE (3250 3375);
FORCEPROP 1 LAST BODY_TYPE PLUMBING
J 0
(3250 3425);
DISPLAY 0.872340 (3250 3425);
PAINT GREEN (3250 3425);
DISPLAY INVISIBLE (3250 3425);
FORCEPROP 1 LAST HDL_TAP TRUE
J 0
(3575 3250);
DISPLAY 0.872340 (3575 3250);
DISPLAY INVISIBLE (3575 3250);
FORCEPROP 1 LAST PATH I154
J 0
(3248 3375);
DISPLAY 0.872340 (3248 3375);
PAINT GREEN (3248 3375);
DISPLAY INVISIBLE (3248 3375);
FORCEADD TAP..1
(3250 3575);
FORCEPROP 3 LASTPIN (3200 3575) SIG_NAME M_B_CPU0_SA_DQS_DP<1>
J 0
(3210 3585);
DISPLAY 0.659574 (3210 3585);
PAINT MONO (3210 3585);
DISPLAY INVISIBLE (3210 3585);
FORCEPROP 1 LASTPIN (3200 3575) BN 1
J 0
(3188 3583);
DISPLAY 0.680851 (3188 3583);
PAINT GREEN (3188 3583);
FORCEPROP 2 LAST CDS_LIB standard
J 0
(3250 3575);
DISPLAY INVISIBLE (3250 3575);
FORCEPROP 1 LAST BODY_TYPE PLUMBING
J 0
(3250 3625);
DISPLAY 0.872340 (3250 3625);
PAINT GREEN (3250 3625);
DISPLAY INVISIBLE (3250 3625);
FORCEPROP 1 LAST HDL_TAP TRUE
J 0
(3575 3450);
DISPLAY 0.872340 (3575 3450);
DISPLAY INVISIBLE (3575 3450);
FORCEPROP 1 LAST PATH I155
J 0
(3248 3575);
DISPLAY 0.872340 (3248 3575);
PAINT GREEN (3248 3575);
DISPLAY INVISIBLE (3248 3575);
FORCEADD TAP..1
(3250 3525);
FORCEPROP 3 LASTPIN (3200 3525) SIG_NAME M_B_CPU0_SA_DQS_DP<0>
J 0
(3210 3535);
DISPLAY 0.659574 (3210 3535);
PAINT MONO (3210 3535);
DISPLAY INVISIBLE (3210 3535);
FORCEPROP 1 LASTPIN (3200 3525) BN 0
J 0
(3188 3533);
DISPLAY 0.680851 (3188 3533);
PAINT GREEN (3188 3533);
FORCEPROP 2 LAST CDS_LIB standard
J 0
(3250 3525);
DISPLAY INVISIBLE (3250 3525);
FORCEPROP 1 LAST BODY_TYPE PLUMBING
J 0
(3250 3575);
DISPLAY 0.872340 (3250 3575);
PAINT GREEN (3250 3575);
DISPLAY INVISIBLE (3250 3575);
FORCEPROP 1 LAST HDL_TAP TRUE
J 0
(3575 3400);
DISPLAY 0.872340 (3575 3400);
DISPLAY INVISIBLE (3575 3400);
FORCEPROP 1 LAST PATH I156
J 0
(3248 3525);
DISPLAY 0.872340 (3248 3525);
PAINT GREEN (3248 3525);
DISPLAY INVISIBLE (3248 3525);
FORCEADD TAP..1
(3250 3725);
FORCEPROP 3 LASTPIN (3200 3725) SIG_NAME M_B_CPU0_SA_DQS_DP<4>
J 0
(3210 3735);
DISPLAY 0.659574 (3210 3735);
PAINT MONO (3210 3735);
DISPLAY INVISIBLE (3210 3735);
FORCEPROP 1 LASTPIN (3200 3725) BN 4
J 0
(3188 3733);
DISPLAY 0.680851 (3188 3733);
PAINT GREEN (3188 3733);
FORCEPROP 2 LAST CDS_LIB standard
J 0
(3250 3725);
DISPLAY INVISIBLE (3250 3725);
FORCEPROP 1 LAST BODY_TYPE PLUMBING
J 0
(3250 3775);
DISPLAY 0.872340 (3250 3775);
PAINT GREEN (3250 3775);
DISPLAY INVISIBLE (3250 3775);
FORCEPROP 1 LAST HDL_TAP TRUE
J 0
(3575 3600);
DISPLAY 0.872340 (3575 3600);
DISPLAY INVISIBLE (3575 3600);
FORCEPROP 1 LAST PATH I157
J 0
(3248 3725);
DISPLAY 0.872340 (3248 3725);
PAINT GREEN (3248 3725);
DISPLAY INVISIBLE (3248 3725);
FORCEADD TAP..1
(3250 3625);
FORCEPROP 3 LASTPIN (3200 3625) SIG_NAME M_B_CPU0_SA_DQS_DP<2>
J 0
(3210 3635);
DISPLAY 0.659574 (3210 3635);
PAINT MONO (3210 3635);
DISPLAY INVISIBLE (3210 3635);
FORCEPROP 1 LASTPIN (3200 3625) BN 2
J 0
(3188 3633);
DISPLAY 0.680851 (3188 3633);
PAINT GREEN (3188 3633);
FORCEPROP 2 LAST CDS_LIB standard
J 0
(3250 3625);
DISPLAY INVISIBLE (3250 3625);
FORCEPROP 1 LAST BODY_TYPE PLUMBING
J 0
(3250 3675);
DISPLAY 0.872340 (3250 3675);
PAINT GREEN (3250 3675);
DISPLAY INVISIBLE (3250 3675);
FORCEPROP 1 LAST HDL_TAP TRUE
J 0
(3575 3500);
DISPLAY 0.872340 (3575 3500);
DISPLAY INVISIBLE (3575 3500);
FORCEPROP 1 LAST PATH I158
J 0
(3248 3625);
DISPLAY 0.872340 (3248 3625);
PAINT GREEN (3248 3625);
DISPLAY INVISIBLE (3248 3625);
FORCEADD TAP..1
(3250 3675);
FORCEPROP 3 LASTPIN (3200 3675) SIG_NAME M_B_CPU0_SA_DQS_DP<3>
J 0
(3210 3685);
DISPLAY 0.659574 (3210 3685);
PAINT MONO (3210 3685);
DISPLAY INVISIBLE (3210 3685);
FORCEPROP 1 LASTPIN (3200 3675) BN 3
J 0
(3188 3683);
DISPLAY 0.680851 (3188 3683);
PAINT GREEN (3188 3683);
FORCEPROP 2 LAST CDS_LIB standard
J 0
(3250 3675);
DISPLAY INVISIBLE (3250 3675);
FORCEPROP 1 LAST BODY_TYPE PLUMBING
J 0
(3250 3725);
DISPLAY 0.872340 (3250 3725);
PAINT GREEN (3250 3725);
DISPLAY INVISIBLE (3250 3725);
FORCEPROP 1 LAST HDL_TAP TRUE
J 0
(3575 3550);
DISPLAY 0.872340 (3575 3550);
DISPLAY INVISIBLE (3575 3550);
FORCEPROP 1 LAST PATH I159
J 0
(3248 3675);
DISPLAY 0.872340 (3248 3675);
PAINT GREEN (3248 3675);
DISPLAY INVISIBLE (3248 3675);
FORCEADD TAP..1
R 2
(-175 425);
FORCEPROP 3 LASTPIN (-125 425) SIG_NAME M_B_CPU0_SB_DQ<0>
J 0
(-115 435);
DISPLAY 0.659574 (-115 435);
PAINT MONO (-115 435);
DISPLAY INVISIBLE (-115 435);
FORCEPROP 1 LASTPIN (-125 425) BN 0
J 2
(-113 433);
DISPLAY 0.680851 (-113 433);
PAINT GREEN (-113 433);
FORCEPROP 2 LAST CDS_LIB standard
J 0
(-175 425);
DISPLAY INVISIBLE (-175 425);
FORCEPROP 1 LAST BODY_TYPE PLUMBING
J 2
(-175 475);
DISPLAY 0.872340 (-175 475);
PAINT GREEN (-175 475);
DISPLAY INVISIBLE (-175 475);
FORCEPROP 1 LAST HDL_TAP TRUE
J 2
(-500 300);
DISPLAY 0.872340 (-500 300);
DISPLAY INVISIBLE (-500 300);
FORCEPROP 1 LAST PATH I16
J 2
(-173 425);
DISPLAY 0.872340 (-173 425);
PAINT GREEN (-173 425);
DISPLAY INVISIBLE (-173 425);
FORCEADD TAP..1
(3250 3825);
FORCEPROP 3 LASTPIN (3200 3825) SIG_NAME M_B_CPU0_SA_DQS_DP<6>
J 0
(3210 3835);
DISPLAY 0.659574 (3210 3835);
PAINT MONO (3210 3835);
DISPLAY INVISIBLE (3210 3835);
FORCEPROP 1 LASTPIN (3200 3825) BN 6
J 0
(3188 3833);
DISPLAY 0.680851 (3188 3833);
PAINT GREEN (3188 3833);
FORCEPROP 2 LAST CDS_LIB standard
J 0
(3250 3825);
DISPLAY INVISIBLE (3250 3825);
FORCEPROP 1 LAST BODY_TYPE PLUMBING
J 0
(3250 3875);
DISPLAY 0.872340 (3250 3875);
PAINT GREEN (3250 3875);
DISPLAY INVISIBLE (3250 3875);
FORCEPROP 1 LAST HDL_TAP TRUE
J 0
(3575 3700);
DISPLAY 0.872340 (3575 3700);
DISPLAY INVISIBLE (3575 3700);
FORCEPROP 1 LAST PATH I160
J 0
(3248 3825);
DISPLAY 0.872340 (3248 3825);
PAINT GREEN (3248 3825);
DISPLAY INVISIBLE (3248 3825);
FORCEADD TAP..1
(3250 3775);
FORCEPROP 3 LASTPIN (3200 3775) SIG_NAME M_B_CPU0_SA_DQS_DP<5>
J 0
(3210 3785);
DISPLAY 0.659574 (3210 3785);
PAINT MONO (3210 3785);
DISPLAY INVISIBLE (3210 3785);
FORCEPROP 1 LASTPIN (3200 3775) BN 5
J 0
(3188 3783);
DISPLAY 0.680851 (3188 3783);
PAINT GREEN (3188 3783);
FORCEPROP 2 LAST CDS_LIB standard
J 0
(3250 3775);
DISPLAY INVISIBLE (3250 3775);
FORCEPROP 1 LAST BODY_TYPE PLUMBING
J 0
(3250 3825);
DISPLAY 0.872340 (3250 3825);
PAINT GREEN (3250 3825);
DISPLAY INVISIBLE (3250 3825);
FORCEPROP 1 LAST HDL_TAP TRUE
J 0
(3575 3650);
DISPLAY 0.872340 (3575 3650);
DISPLAY INVISIBLE (3575 3650);
FORCEPROP 1 LAST PATH I161
J 0
(3248 3775);
DISPLAY 0.872340 (3248 3775);
PAINT GREEN (3248 3775);
DISPLAY INVISIBLE (3248 3775);
FORCEADD OFFPAGE..3
(4350 2300);
FORCEPROP 2 LAST $XR1 85 
J 0
(4654 2300);
DISPLAY 0.638298 (4654 2300);
PAINT MONO (4654 2300);
FORCEPROP 2 LAST $XR0 84 
J 0
(4564 2300);
DISPLAY 0.638298 (4564 2300);
PAINT MONO (4564 2300);
FORCEPROP 2 LAST CDS_LIB standard
J 2
(4350 2300);
DISPLAY INVISIBLE (4350 2300);
FORCEPROP 1 LAST OFFPAGE TRUE
J 0
(4675 2175);
DISPLAY 0.872340 (4675 2175);
DISPLAY INVISIBLE (4675 2175);
FORCEPROP 1 LAST COMMENT_BODY TRUE
J 0
(4300 2200);
DISPLAY 0.872340 (4300 2200);
PAINT GREEN (4300 2200);
DISPLAY INVISIBLE (4300 2200);
FORCEPROP 2 LAST PATH I162
J 0
(4550 2375);
DISPLAY 1.021277 (4550 2375);
DISPLAY INVISIBLE (4550 2375);
FORCEADD OFFPAGE..3
(4350 2850);
FORCEPROP 2 LAST $XR1 85 
J 0
(4654 2850);
DISPLAY 0.638298 (4654 2850);
PAINT MONO (4654 2850);
FORCEPROP 2 LAST $XR0 84 
J 0
(4564 2850);
DISPLAY 0.638298 (4564 2850);
PAINT MONO (4564 2850);
FORCEPROP 2 LAST CDS_LIB standard
J 2
(4350 2850);
DISPLAY INVISIBLE (4350 2850);
FORCEPROP 1 LAST OFFPAGE TRUE
J 0
(4675 2725);
DISPLAY 0.872340 (4675 2725);
DISPLAY INVISIBLE (4675 2725);
FORCEPROP 1 LAST COMMENT_BODY TRUE
J 0
(4300 2750);
DISPLAY 0.872340 (4300 2750);
PAINT GREEN (4300 2750);
DISPLAY INVISIBLE (4300 2750);
FORCEPROP 2 LAST PATH I163
J 0
(4550 2925);
DISPLAY 1.021277 (4550 2925);
DISPLAY INVISIBLE (4550 2925);
FORCEADD OFFPAGE..3
(4350 3450);
FORCEPROP 2 LAST $XR1 85 
J 0
(4654 3450);
DISPLAY 0.638298 (4654 3450);
PAINT MONO (4654 3450);
FORCEPROP 2 LAST $XR0 84 
J 0
(4564 3450);
DISPLAY 0.638298 (4564 3450);
PAINT MONO (4564 3450);
FORCEPROP 2 LAST CDS_LIB standard
J 2
(4350 3450);
DISPLAY INVISIBLE (4350 3450);
FORCEPROP 1 LAST OFFPAGE TRUE
J 0
(4675 3325);
DISPLAY 0.872340 (4675 3325);
DISPLAY INVISIBLE (4675 3325);
FORCEPROP 1 LAST COMMENT_BODY TRUE
J 0
(4300 3350);
DISPLAY 0.872340 (4300 3350);
PAINT GREEN (4300 3350);
DISPLAY INVISIBLE (4300 3350);
FORCEPROP 2 LAST PATH I164
J 0
(4550 3525);
DISPLAY 1.021277 (4550 3525);
DISPLAY INVISIBLE (4550 3525);
FORCEADD TAP..1
(3250 3875);
FORCEPROP 3 LASTPIN (3200 3875) SIG_NAME M_B_CPU0_SA_DQS_DP<7>
J 0
(3210 3885);
DISPLAY 0.659574 (3210 3885);
PAINT MONO (3210 3885);
DISPLAY INVISIBLE (3210 3885);
FORCEPROP 1 LASTPIN (3200 3875) BN 7
J 0
(3188 3883);
DISPLAY 0.680851 (3188 3883);
PAINT GREEN (3188 3883);
FORCEPROP 2 LAST CDS_LIB standard
J 0
(3250 3875);
DISPLAY INVISIBLE (3250 3875);
FORCEPROP 1 LAST BODY_TYPE PLUMBING
J 0
(3250 3925);
DISPLAY 0.872340 (3250 3925);
PAINT GREEN (3250 3925);
DISPLAY INVISIBLE (3250 3925);
FORCEPROP 1 LAST HDL_TAP TRUE
J 0
(3575 3750);
DISPLAY 0.872340 (3575 3750);
DISPLAY INVISIBLE (3575 3750);
FORCEPROP 1 LAST PATH I165
J 0
(3248 3875);
DISPLAY 0.872340 (3248 3875);
PAINT GREEN (3248 3875);
DISPLAY INVISIBLE (3248 3875);
FORCEADD TAP..1
(3250 3925);
FORCEPROP 3 LASTPIN (3200 3925) SIG_NAME M_B_CPU0_SA_DQS_DP<8>
J 0
(3210 3935);
DISPLAY 0.659574 (3210 3935);
PAINT MONO (3210 3935);
DISPLAY INVISIBLE (3210 3935);
FORCEPROP 1 LASTPIN (3200 3925) BN 8
J 0
(3188 3933);
DISPLAY 0.680851 (3188 3933);
PAINT GREEN (3188 3933);
FORCEPROP 2 LAST CDS_LIB standard
J 0
(3250 3925);
DISPLAY INVISIBLE (3250 3925);
FORCEPROP 1 LAST BODY_TYPE PLUMBING
J 0
(3250 3975);
DISPLAY 0.872340 (3250 3975);
PAINT GREEN (3250 3975);
DISPLAY INVISIBLE (3250 3975);
FORCEPROP 1 LAST HDL_TAP TRUE
J 0
(3575 3800);
DISPLAY 0.872340 (3575 3800);
DISPLAY INVISIBLE (3575 3800);
FORCEPROP 1 LAST PATH I166
J 0
(3248 3925);
DISPLAY 0.872340 (3248 3925);
PAINT GREEN (3248 3925);
DISPLAY INVISIBLE (3248 3925);
FORCEADD TAP..1
(3250 3975);
FORCEPROP 3 LASTPIN (3200 3975) SIG_NAME M_B_CPU0_SA_DQS_DP<9>
J 0
(3210 3985);
DISPLAY 0.659574 (3210 3985);
PAINT MONO (3210 3985);
DISPLAY INVISIBLE (3210 3985);
FORCEPROP 1 LASTPIN (3200 3975) BN 9
J 0
(3188 3983);
DISPLAY 0.680851 (3188 3983);
PAINT GREEN (3188 3983);
FORCEPROP 2 LAST CDS_LIB standard
J 0
(3250 3975);
DISPLAY INVISIBLE (3250 3975);
FORCEPROP 1 LAST BODY_TYPE PLUMBING
J 0
(3250 4025);
DISPLAY 0.872340 (3250 4025);
PAINT GREEN (3250 4025);
DISPLAY INVISIBLE (3250 4025);
FORCEPROP 1 LAST HDL_TAP TRUE
J 0
(3575 3850);
DISPLAY 0.872340 (3575 3850);
DISPLAY INVISIBLE (3575 3850);
FORCEPROP 1 LAST PATH I167
J 0
(3248 3975);
DISPLAY 0.872340 (3248 3975);
PAINT GREEN (3248 3975);
DISPLAY INVISIBLE (3248 3975);
FORCEADD OFFPAGE..3
(4350 4000);
FORCEPROP 2 LAST $XR1 85 
J 0
(4654 4000);
DISPLAY 0.638298 (4654 4000);
PAINT MONO (4654 4000);
FORCEPROP 2 LAST $XR0 84 
J 0
(4564 4000);
DISPLAY 0.638298 (4564 4000);
PAINT MONO (4564 4000);
FORCEPROP 2 LAST CDS_LIB standard
J 2
(4350 4000);
DISPLAY INVISIBLE (4350 4000);
FORCEPROP 1 LAST OFFPAGE TRUE
J 0
(4675 3875);
DISPLAY 0.872340 (4675 3875);
DISPLAY INVISIBLE (4675 3875);
FORCEPROP 1 LAST COMMENT_BODY TRUE
J 0
(4300 3900);
DISPLAY 0.872340 (4300 3900);
PAINT GREEN (4300 3900);
DISPLAY INVISIBLE (4300 3900);
FORCEPROP 2 LAST PATH I168
J 0
(4550 4075);
DISPLAY 1.021277 (4550 4075);
DISPLAY INVISIBLE (4550 4075);
FORCEADD SOCKET4677_AZIF0045P001C01CS..9
(1550 1875);
FORCEPROP 1 LAST PART_NUMBER DGA^7000023
J 0
(450 4225);
DISPLAY 0.723404 (450 4225);
PAINT GREEN (450 4225);
DISPLAY INVISIBLE (450 4225);
FORCEPROP 2 LAST PART_TYPE SMLF
J 0
(450 4400);
DISPLAY 1.021277 (450 4400);
FORCEPROP 2 LAST VALUE SOCKET4677_AZIF0045-P001C01CS
J 0
(450 4350);
DISPLAY 1.021277 (450 4350);
FORCEPROP 1 LAST MATERIAL IO
J 0
(450 4150);
DISPLAY 0.723404 (450 4150);
PAINT GREEN (450 4150);
FORCEPROP 1 LAST $LOCATION U2
J 0
(450 4300);
DISPLAY 0.723404 (450 4300);
PAINT GREEN (450 4300);
FORCEPROP 0 LASTPIN (2775 25) $PN AL48
J 0
(2785 35);
DISPLAY 0.680851 (2785 35);
PAINT MONO (2785 35);
FORCEPROP 0 LASTPIN (2775 75) $PN AK47
J 0
(2785 85);
DISPLAY 0.680851 (2785 85);
PAINT MONO (2785 85);
FORCEPROP 0 LASTPIN (2775 -225) $PN AV49
J 0
(2785 -215);
DISPLAY 0.680851 (2785 -215);
PAINT MONO (2785 -215);
FORCEPROP 0 LASTPIN (2775 -125) $PN AN48
J 0
(2785 -115);
DISPLAY 0.680851 (2785 -115);
PAINT MONO (2785 -115);
FORCEPROP 0 LASTPIN (2775 -75) $PN AP47
J 0
(2785 -65);
DISPLAY 0.680851 (2785 -65);
PAINT MONO (2785 -65);
FORCEPROP 0 LASTPIN (325 -225) $PN R45
J 2
(315 -215);
DISPLAY 0.680851 (315 -215);
PAINT MONO (315 -215);
FORCEPROP 0 LASTPIN (325 -175) $PN W45
J 2
(315 -165);
DISPLAY 0.680851 (315 -165);
PAINT MONO (315 -165);
FORCEPROP 0 LASTPIN (325 -125) $PN U45
J 2
(315 -115);
DISPLAY 0.680851 (315 -115);
PAINT MONO (315 -115);
FORCEPROP 0 LASTPIN (325 -75) $PN AA45
J 2
(315 -65);
DISPLAY 0.680851 (315 -65);
PAINT MONO (315 -65);
FORCEPROP 0 LASTPIN (2775 1375) $PN H49
J 0
(2785 1385);
DISPLAY 0.680851 (2785 1385);
PAINT MONO (2785 1385);
FORCEPROP 0 LASTPIN (2775 1425) $PN P49
J 0
(2785 1435);
DISPLAY 0.680851 (2785 1435);
PAINT MONO (2785 1435);
FORCEPROP 0 LASTPIN (2775 1475) $PN J48
J 0
(2785 1485);
DISPLAY 0.680851 (2785 1485);
PAINT MONO (2785 1485);
FORCEPROP 0 LASTPIN (2775 1525) $PN N48
J 0
(2785 1535);
DISPLAY 0.680851 (2785 1535);
PAINT MONO (2785 1535);
FORCEPROP 0 LASTPIN (2775 1575) $PN K47
J 0
(2785 1585);
DISPLAY 0.680851 (2785 1585);
PAINT MONO (2785 1585);
FORCEPROP 0 LASTPIN (2775 1625) $PN M47
J 0
(2785 1635);
DISPLAY 0.680851 (2785 1635);
PAINT MONO (2785 1635);
FORCEPROP 0 LASTPIN (2775 1675) $PN Y44
J 0
(2785 1685);
DISPLAY 0.680851 (2785 1685);
PAINT MONO (2785 1685);
FORCEPROP 0 LASTPIN (325 2425) $PN K75
J 2
(315 2435);
DISPLAY 0.680851 (315 2435);
PAINT MONO (315 2435);
FORCEPROP 0 LASTPIN (325 2475) $PN J74
J 2
(315 2485);
DISPLAY 0.680851 (315 2485);
PAINT MONO (315 2485);
FORCEPROP 0 LASTPIN (325 2525) $PN M75
J 2
(315 2535);
DISPLAY 0.680851 (315 2535);
PAINT MONO (315 2535);
FORCEPROP 0 LASTPIN (325 2575) $PN N74
J 2
(315 2585);
DISPLAY 0.680851 (315 2585);
PAINT MONO (315 2585);
FORCEPROP 0 LASTPIN (325 2625) $PN J72
J 2
(315 2635);
DISPLAY 0.680851 (315 2635);
PAINT MONO (315 2635);
FORCEPROP 0 LASTPIN (325 2675) $PN K71
J 2
(315 2685);
DISPLAY 0.680851 (315 2685);
PAINT MONO (315 2685);
FORCEPROP 0 LASTPIN (325 2725) $PN N72
J 2
(315 2735);
DISPLAY 0.680851 (315 2735);
PAINT MONO (315 2735);
FORCEPROP 0 LASTPIN (325 2775) $PN M71
J 2
(315 2785);
DISPLAY 0.680851 (315 2785);
PAINT MONO (315 2785);
FORCEPROP 0 LASTPIN (325 2825) $PN U72
J 2
(315 2835);
DISPLAY 0.680851 (315 2835);
PAINT MONO (315 2835);
FORCEPROP 0 LASTPIN (325 2875) $PN T71
J 2
(315 2885);
DISPLAY 0.680851 (315 2885);
PAINT MONO (315 2885);
FORCEPROP 0 LASTPIN (325 2925) $PN W72
J 2
(315 2935);
DISPLAY 0.680851 (315 2935);
PAINT MONO (315 2935);
FORCEPROP 0 LASTPIN (325 2975) $PN Y71
J 2
(315 2985);
DISPLAY 0.680851 (315 2985);
PAINT MONO (315 2985);
FORCEPROP 0 LASTPIN (325 3025) $PN T69
J 2
(315 3035);
DISPLAY 0.680851 (315 3035);
PAINT MONO (315 3035);
FORCEPROP 0 LASTPIN (325 3075) $PN U68
J 2
(315 3085);
DISPLAY 0.680851 (315 3085);
PAINT MONO (315 3085);
FORCEPROP 0 LASTPIN (325 3125) $PN Y69
J 2
(315 3135);
DISPLAY 0.680851 (315 3135);
PAINT MONO (315 3135);
FORCEPROP 0 LASTPIN (325 3175) $PN W68
J 2
(315 3185);
DISPLAY 0.680851 (315 3185);
PAINT MONO (315 3185);
FORCEPROP 0 LASTPIN (325 3225) $PN K63
J 2
(315 3235);
DISPLAY 0.680851 (315 3235);
PAINT MONO (315 3235);
FORCEPROP 0 LASTPIN (325 3275) $PN J62
J 2
(315 3285);
DISPLAY 0.680851 (315 3285);
PAINT MONO (315 3285);
FORCEPROP 0 LASTPIN (325 3325) $PN M63
J 2
(315 3335);
DISPLAY 0.680851 (315 3335);
PAINT MONO (315 3335);
FORCEPROP 0 LASTPIN (325 3375) $PN N62
J 2
(315 3385);
DISPLAY 0.680851 (315 3385);
PAINT MONO (315 3385);
FORCEPROP 0 LASTPIN (325 3425) $PN J60
J 2
(315 3435);
DISPLAY 0.680851 (315 3435);
PAINT MONO (315 3435);
FORCEPROP 0 LASTPIN (325 3475) $PN K59
J 2
(315 3485);
DISPLAY 0.680851 (315 3485);
PAINT MONO (315 3485);
FORCEPROP 0 LASTPIN (325 3525) $PN N60
J 2
(315 3535);
DISPLAY 0.680851 (315 3535);
PAINT MONO (315 3535);
FORCEPROP 0 LASTPIN (325 3575) $PN M59
J 2
(315 3585);
DISPLAY 0.680851 (315 3585);
PAINT MONO (315 3585);
FORCEPROP 0 LASTPIN (325 3625) $PN U60
J 2
(315 3635);
DISPLAY 0.680851 (315 3635);
PAINT MONO (315 3635);
FORCEPROP 0 LASTPIN (325 3675) $PN T59
J 2
(315 3685);
DISPLAY 0.680851 (315 3685);
PAINT MONO (315 3685);
FORCEPROP 0 LASTPIN (325 3725) $PN W60
J 2
(315 3735);
DISPLAY 0.680851 (315 3735);
PAINT MONO (315 3735);
FORCEPROP 0 LASTPIN (325 3775) $PN Y59
J 2
(315 3785);
DISPLAY 0.680851 (315 3785);
PAINT MONO (315 3785);
FORCEPROP 0 LASTPIN (325 3825) $PN T57
J 2
(315 3835);
DISPLAY 0.680851 (315 3835);
PAINT MONO (315 3835);
FORCEPROP 0 LASTPIN (325 3875) $PN U56
J 2
(315 3885);
DISPLAY 0.680851 (315 3885);
PAINT MONO (315 3885);
FORCEPROP 0 LASTPIN (325 3925) $PN Y57
J 2
(315 3935);
DISPLAY 0.680851 (315 3935);
PAINT MONO (315 3935);
FORCEPROP 0 LASTPIN (325 3975) $PN W56
J 2
(315 3985);
DISPLAY 0.680851 (315 3985);
PAINT MONO (315 3985);
FORCEPROP 0 LASTPIN (2775 2975) $PN H73
J 0
(2785 2985);
DISPLAY 0.680851 (2785 2985);
PAINT MONO (2785 2985);
FORCEPROP 0 LASTPIN (2775 3025) $PN R70
J 0
(2785 3035);
DISPLAY 0.680851 (2785 3035);
PAINT MONO (2785 3035);
FORCEPROP 0 LASTPIN (2775 3075) $PN H61
J 0
(2785 3085);
DISPLAY 0.680851 (2785 3085);
PAINT MONO (2785 3085);
FORCEPROP 0 LASTPIN (2775 3125) $PN R58
J 0
(2785 3135);
DISPLAY 0.680851 (2785 3135);
PAINT MONO (2785 3135);
FORCEPROP 0 LASTPIN (2775 3175) $PN H55
J 0
(2785 3185);
DISPLAY 0.680851 (2785 3185);
PAINT MONO (2785 3185);
FORCEPROP 0 LASTPIN (2775 3225) $PN M73
J 0
(2785 3235);
DISPLAY 0.680851 (2785 3235);
PAINT MONO (2785 3235);
FORCEPROP 0 LASTPIN (2775 3275) $PN AA70
J 0
(2785 3285);
DISPLAY 0.680851 (2785 3285);
PAINT MONO (2785 3285);
FORCEPROP 0 LASTPIN (2775 3325) $PN M61
J 0
(2785 3335);
DISPLAY 0.680851 (2785 3335);
PAINT MONO (2785 3335);
FORCEPROP 0 LASTPIN (2775 3375) $PN AA58
J 0
(2785 3385);
DISPLAY 0.680851 (2785 3385);
PAINT MONO (2785 3385);
FORCEPROP 0 LASTPIN (2775 3425) $PN M55
J 0
(2785 3435);
DISPLAY 0.680851 (2785 3435);
PAINT MONO (2785 3435);
FORCEPROP 0 LASTPIN (2775 3525) $PN K73
J 0
(2785 3535);
DISPLAY 0.680851 (2785 3535);
PAINT MONO (2785 3535);
FORCEPROP 0 LASTPIN (2775 3575) $PN U70
J 0
(2785 3585);
DISPLAY 0.680851 (2785 3585);
PAINT MONO (2785 3585);
FORCEPROP 0 LASTPIN (2775 3625) $PN K61
J 0
(2785 3635);
DISPLAY 0.680851 (2785 3635);
PAINT MONO (2785 3635);
FORCEPROP 0 LASTPIN (2775 3675) $PN U58
J 0
(2785 3685);
DISPLAY 0.680851 (2785 3685);
PAINT MONO (2785 3685);
FORCEPROP 0 LASTPIN (2775 3725) $PN K55
J 0
(2785 3735);
DISPLAY 0.680851 (2785 3735);
PAINT MONO (2785 3735);
FORCEPROP 0 LASTPIN (2775 3775) $PN P73
J 0
(2785 3785);
DISPLAY 0.680851 (2785 3785);
PAINT MONO (2785 3785);
FORCEPROP 0 LASTPIN (2775 3825) $PN W70
J 0
(2785 3835);
DISPLAY 0.680851 (2785 3835);
PAINT MONO (2785 3835);
FORCEPROP 0 LASTPIN (2775 3875) $PN P61
J 0
(2785 3885);
DISPLAY 0.680851 (2785 3885);
PAINT MONO (2785 3885);
FORCEPROP 0 LASTPIN (2775 3925) $PN W58
J 0
(2785 3935);
DISPLAY 0.680851 (2785 3935);
PAINT MONO (2785 3935);
FORCEPROP 0 LASTPIN (2775 3975) $PN P55
J 0
(2785 3985);
DISPLAY 0.680851 (2785 3985);
PAINT MONO (2785 3985);
FORCEPROP 0 LASTPIN (325 2025) $PN K57
J 2
(315 2035);
DISPLAY 0.680851 (315 2035);
PAINT MONO (315 2035);
FORCEPROP 0 LASTPIN (325 2075) $PN J56
J 2
(315 2085);
DISPLAY 0.680851 (315 2085);
PAINT MONO (315 2085);
FORCEPROP 0 LASTPIN (325 2125) $PN M57
J 2
(315 2135);
DISPLAY 0.680851 (315 2135);
PAINT MONO (315 2135);
FORCEPROP 0 LASTPIN (325 2175) $PN N56
J 2
(315 2185);
DISPLAY 0.680851 (315 2185);
PAINT MONO (315 2185);
FORCEPROP 0 LASTPIN (325 2225) $PN J54
J 2
(315 2235);
DISPLAY 0.680851 (315 2235);
PAINT MONO (315 2235);
FORCEPROP 0 LASTPIN (325 2275) $PN K53
J 2
(315 2285);
DISPLAY 0.680851 (315 2285);
PAINT MONO (315 2285);
FORCEPROP 0 LASTPIN (325 2325) $PN N54
J 2
(315 2335);
DISPLAY 0.680851 (315 2335);
PAINT MONO (315 2335);
FORCEPROP 0 LASTPIN (325 2375) $PN M53
J 2
(315 2385);
DISPLAY 0.680851 (315 2385);
PAINT MONO (315 2385);
FORCEPROP 0 LASTPIN (2775 1325) $PN W43
J 0
(2785 1335);
DISPLAY 0.680851 (2785 1335);
PAINT MONO (2785 1335);
FORCEPROP 0 LASTPIN (2775 875) $PN T44
J 0
(2785 885);
DISPLAY 0.680851 (2785 885);
PAINT MONO (2785 885);
FORCEPROP 0 LASTPIN (2775 925) $PN U43
J 0
(2785 935);
DISPLAY 0.680851 (2785 935);
PAINT MONO (2785 935);
FORCEPROP 0 LASTPIN (2775 975) $PN K44
J 0
(2785 985);
DISPLAY 0.680851 (2785 985);
PAINT MONO (2785 985);
FORCEPROP 0 LASTPIN (2775 1025) $PN M44
J 0
(2785 1035);
DISPLAY 0.680851 (2785 1035);
PAINT MONO (2785 1035);
FORCEPROP 0 LASTPIN (2775 1075) $PN J43
J 0
(2785 1085);
DISPLAY 0.680851 (2785 1085);
PAINT MONO (2785 1085);
FORCEPROP 0 LASTPIN (2775 1125) $PN N43
J 0
(2785 1135);
DISPLAY 0.680851 (2785 1135);
PAINT MONO (2785 1135);
FORCEPROP 0 LASTPIN (2775 1175) $PN H42
J 0
(2785 1185);
DISPLAY 0.680851 (2785 1185);
PAINT MONO (2785 1185);
FORCEPROP 0 LASTPIN (325 425) $PN U29
J 2
(315 435);
DISPLAY 0.680851 (315 435);
PAINT MONO (315 435);
FORCEPROP 0 LASTPIN (325 475) $PN T28
J 2
(315 485);
DISPLAY 0.680851 (315 485);
PAINT MONO (315 485);
FORCEPROP 0 LASTPIN (325 525) $PN W29
J 2
(315 535);
DISPLAY 0.680851 (315 535);
PAINT MONO (315 535);
FORCEPROP 0 LASTPIN (325 575) $PN Y28
J 2
(315 585);
DISPLAY 0.680851 (315 585);
PAINT MONO (315 585);
FORCEPROP 0 LASTPIN (325 625) $PN T26
J 2
(315 635);
DISPLAY 0.680851 (315 635);
PAINT MONO (315 635);
FORCEPROP 0 LASTPIN (325 675) $PN U25
J 2
(315 685);
DISPLAY 0.680851 (315 685);
PAINT MONO (315 685);
FORCEPROP 0 LASTPIN (325 725) $PN Y26
J 2
(315 735);
DISPLAY 0.680851 (315 735);
PAINT MONO (315 735);
FORCEPROP 0 LASTPIN (325 775) $PN W25
J 2
(315 785);
DISPLAY 0.680851 (315 785);
PAINT MONO (315 785);
FORCEPROP 0 LASTPIN (325 825) $PN K26
J 2
(315 835);
DISPLAY 0.680851 (315 835);
PAINT MONO (315 835);
FORCEPROP 0 LASTPIN (325 875) $PN J25
J 2
(315 885);
DISPLAY 0.680851 (315 885);
PAINT MONO (315 885);
FORCEPROP 0 LASTPIN (325 925) $PN M26
J 2
(315 935);
DISPLAY 0.680851 (315 935);
PAINT MONO (315 935);
FORCEPROP 0 LASTPIN (325 975) $PN N25
J 2
(315 985);
DISPLAY 0.680851 (315 985);
PAINT MONO (315 985);
FORCEPROP 0 LASTPIN (325 1025) $PN J23
J 2
(315 1035);
DISPLAY 0.680851 (315 1035);
PAINT MONO (315 1035);
FORCEPROP 0 LASTPIN (325 1075) $PN K22
J 2
(315 1085);
DISPLAY 0.680851 (315 1085);
PAINT MONO (315 1085);
FORCEPROP 0 LASTPIN (325 1125) $PN N23
J 2
(315 1135);
DISPLAY 0.680851 (315 1135);
PAINT MONO (315 1135);
FORCEPROP 0 LASTPIN (325 1175) $PN M22
J 2
(315 1185);
DISPLAY 0.680851 (315 1185);
PAINT MONO (315 1185);
FORCEPROP 0 LASTPIN (325 1225) $PN K20
J 2
(315 1235);
DISPLAY 0.680851 (315 1235);
PAINT MONO (315 1235);
FORCEPROP 0 LASTPIN (325 1275) $PN J19
J 2
(315 1285);
DISPLAY 0.680851 (315 1285);
PAINT MONO (315 1285);
FORCEPROP 0 LASTPIN (325 1325) $PN M20
J 2
(315 1335);
DISPLAY 0.680851 (315 1335);
PAINT MONO (315 1335);
FORCEPROP 0 LASTPIN (325 1375) $PN N19
J 2
(315 1385);
DISPLAY 0.680851 (315 1385);
PAINT MONO (315 1385);
FORCEPROP 0 LASTPIN (325 1425) $PN J17
J 2
(315 1435);
DISPLAY 0.680851 (315 1435);
PAINT MONO (315 1435);
FORCEPROP 0 LASTPIN (325 1475) $PN K16
J 2
(315 1485);
DISPLAY 0.680851 (315 1485);
PAINT MONO (315 1485);
FORCEPROP 0 LASTPIN (325 1525) $PN N17
J 2
(315 1535);
DISPLAY 0.680851 (315 1535);
PAINT MONO (315 1535);
FORCEPROP 0 LASTPIN (325 1575) $PN M16
J 2
(315 1585);
DISPLAY 0.680851 (315 1585);
PAINT MONO (315 1585);
FORCEPROP 0 LASTPIN (325 1625) $PN C17
J 2
(315 1635);
DISPLAY 0.680851 (315 1635);
PAINT MONO (315 1635);
FORCEPROP 0 LASTPIN (325 1675) $PN B16
J 2
(315 1685);
DISPLAY 0.680851 (315 1685);
PAINT MONO (315 1685);
FORCEPROP 0 LASTPIN (325 1725) $PN E17
J 2
(315 1735);
DISPLAY 0.680851 (315 1735);
PAINT MONO (315 1735);
FORCEPROP 0 LASTPIN (325 1775) $PN F16
J 2
(315 1785);
DISPLAY 0.680851 (315 1785);
PAINT MONO (315 1785);
FORCEPROP 0 LASTPIN (325 1825) $PN C13
J 2
(315 1835);
DISPLAY 0.680851 (315 1835);
PAINT MONO (315 1835);
FORCEPROP 0 LASTPIN (325 1875) $PN E13
J 2
(315 1885);
DISPLAY 0.680851 (315 1885);
PAINT MONO (315 1885);
FORCEPROP 0 LASTPIN (325 1925) $PN B14
J 2
(315 1935);
DISPLAY 0.680851 (315 1935);
PAINT MONO (315 1935);
FORCEPROP 0 LASTPIN (325 1975) $PN F14
J 2
(315 1985);
DISPLAY 0.680851 (315 1985);
PAINT MONO (315 1985);
FORCEPROP 0 LASTPIN (2775 1825) $PN R27
J 0
(2785 1835);
DISPLAY 0.680851 (2785 1835);
PAINT MONO (2785 1835);
FORCEPROP 0 LASTPIN (2775 1875) $PN H24
J 0
(2785 1885);
DISPLAY 0.680851 (2785 1885);
PAINT MONO (2785 1885);
FORCEPROP 0 LASTPIN (2775 1925) $PN H18
J 0
(2785 1935);
DISPLAY 0.680851 (2785 1935);
PAINT MONO (2785 1935);
FORCEPROP 0 LASTPIN (2775 1975) $PN A15
J 0
(2785 1985);
DISPLAY 0.680851 (2785 1985);
PAINT MONO (2785 1985);
FORCEPROP 0 LASTPIN (2775 2025) $PN P36
J 0
(2785 2035);
DISPLAY 0.680851 (2785 2035);
PAINT MONO (2785 2035);
FORCEPROP 0 LASTPIN (2775 2075) $PN W27
J 0
(2785 2085);
DISPLAY 0.680851 (2785 2085);
PAINT MONO (2785 2085);
FORCEPROP 0 LASTPIN (2775 2125) $PN M24
J 0
(2785 2135);
DISPLAY 0.680851 (2785 2135);
PAINT MONO (2785 2135);
FORCEPROP 0 LASTPIN (2775 2175) $PN M18
J 0
(2785 2185);
DISPLAY 0.680851 (2785 2185);
PAINT MONO (2785 2185);
FORCEPROP 0 LASTPIN (2775 2225) $PN E15
J 0
(2785 2235);
DISPLAY 0.680851 (2785 2235);
PAINT MONO (2785 2235);
FORCEPROP 0 LASTPIN (2775 2275) $PN K36
J 0
(2785 2285);
DISPLAY 0.680851 (2785 2285);
PAINT MONO (2785 2285);
FORCEPROP 0 LASTPIN (2775 2375) $PN U27
J 0
(2785 2385);
DISPLAY 0.680851 (2785 2385);
PAINT MONO (2785 2385);
FORCEPROP 0 LASTPIN (2775 2425) $PN K24
J 0
(2785 2435);
DISPLAY 0.680851 (2785 2435);
PAINT MONO (2785 2435);
FORCEPROP 0 LASTPIN (2775 2475) $PN K18
J 0
(2785 2485);
DISPLAY 0.680851 (2785 2485);
PAINT MONO (2785 2485);
FORCEPROP 0 LASTPIN (2775 2525) $PN C15
J 0
(2785 2535);
DISPLAY 0.680851 (2785 2535);
PAINT MONO (2785 2535);
FORCEPROP 0 LASTPIN (2775 2575) $PN M36
J 0
(2785 2585);
DISPLAY 0.680851 (2785 2585);
PAINT MONO (2785 2585);
FORCEPROP 0 LASTPIN (2775 2625) $PN AA27
J 0
(2785 2635);
DISPLAY 0.680851 (2785 2635);
PAINT MONO (2785 2635);
FORCEPROP 0 LASTPIN (2775 2675) $PN P24
J 0
(2785 2685);
DISPLAY 0.680851 (2785 2685);
PAINT MONO (2785 2685);
FORCEPROP 0 LASTPIN (2775 2725) $PN P18
J 0
(2785 2735);
DISPLAY 0.680851 (2785 2735);
PAINT MONO (2785 2735);
FORCEPROP 0 LASTPIN (2775 2775) $PN G15
J 0
(2785 2785);
DISPLAY 0.680851 (2785 2785);
PAINT MONO (2785 2785);
FORCEPROP 0 LASTPIN (2775 2825) $PN H36
J 0
(2785 2835);
DISPLAY 0.680851 (2785 2835);
PAINT MONO (2785 2835);
FORCEPROP 0 LASTPIN (325 25) $PN J35
J 2
(315 35);
DISPLAY 0.680851 (315 35);
PAINT MONO (315 35);
FORCEPROP 0 LASTPIN (325 75) $PN K34
J 2
(315 85);
DISPLAY 0.680851 (315 85);
PAINT MONO (315 85);
FORCEPROP 0 LASTPIN (325 125) $PN N35
J 2
(315 135);
DISPLAY 0.680851 (315 135);
PAINT MONO (315 135);
FORCEPROP 0 LASTPIN (325 175) $PN M34
J 2
(315 185);
DISPLAY 0.680851 (315 185);
PAINT MONO (315 185);
FORCEPROP 0 LASTPIN (325 225) $PN K38
J 2
(315 235);
DISPLAY 0.680851 (315 235);
PAINT MONO (315 235);
FORCEPROP 0 LASTPIN (325 275) $PN J37
J 2
(315 285);
DISPLAY 0.680851 (315 285);
PAINT MONO (315 285);
FORCEPROP 0 LASTPIN (325 325) $PN M38
J 2
(315 335);
DISPLAY 0.680851 (315 335);
PAINT MONO (315 335);
FORCEPROP 0 LASTPIN (325 375) $PN N37
J 2
(315 385);
DISPLAY 0.680851 (315 385);
PAINT MONO (315 385);
FORCEPROP 0 LASTPIN (2775 825) $PN P42
J 0
(2785 835);
DISPLAY 0.680851 (2785 835);
PAINT MONO (2785 835);
FORCEPROP 0 LASTPIN (2775 525) $PN K51
J 0
(2785 535);
DISPLAY 0.680851 (2785 535);
PAINT MONO (2785 535);
FORCEPROP 0 LASTPIN (2775 575) $PN J50
J 0
(2785 585);
DISPLAY 0.680851 (2785 585);
PAINT MONO (2785 585);
FORCEPROP 0 LASTPIN (2775 625) $PN M51
J 0
(2785 635);
DISPLAY 0.680851 (2785 635);
PAINT MONO (2785 635);
FORCEPROP 0 LASTPIN (2775 675) $PN N50
J 0
(2785 685);
DISPLAY 0.680851 (2785 685);
PAINT MONO (2785 685);
FORCEPROP 0 LASTPIN (2775 225) $PN J41
J 0
(2785 235);
DISPLAY 0.680851 (2785 235);
PAINT MONO (2785 235);
FORCEPROP 0 LASTPIN (2775 275) $PN K40
J 0
(2785 285);
DISPLAY 0.680851 (2785 285);
PAINT MONO (2785 285);
FORCEPROP 0 LASTPIN (2775 325) $PN N41
J 0
(2785 335);
DISPLAY 0.680851 (2785 335);
PAINT MONO (2785 335);
FORCEPROP 0 LASTPIN (2775 375) $PN M40
J 0
(2785 385);
DISPLAY 0.680851 (2785 385);
PAINT MONO (2785 385);
FORCEPROP 2 LAST CDS_LIB pure_quanta
J 0
(1550 1875);
DISPLAY INVISIBLE (1550 1875);
FORCEPROP 1 LAST NEEDS_NO_SIZE TRUE
J 0
(1550 1875);
DISPLAY 0.723404 (1550 1875);
PAINT GREEN (1550 1875);
DISPLAY INVISIBLE (1550 1875);
FORCEPROP 1 LAST CDS_LMAN_SYM_OUTLINE -1100,2250,1050,-2250
J 0
(1550 1875);
DISPLAY 0.468085 (1550 1875);
PAINT GREEN (1550 1875);
DISPLAY INVISIBLE (1550 1875);
FORCEPROP 2 LAST CDS_LOCATION U2
J 0
(450 4450);
DISPLAY 1.021277 (450 4450);
DISPLAY INVISIBLE (450 4450);
FORCEPROP 0 LAST $SEC 9
J 0
(450 4450);
DISPLAY 0.680851 (450 4450);
PAINT MONO (450 4450);
DISPLAY INVISIBLE (450 4450);
FORCEPROP 2 LAST CDS_SEC 9
J 0
(450 4450);
DISPLAY 1.021277 (450 4450);
DISPLAY INVISIBLE (450 4450);
FORCEPROP 1 LAST PATH I169
J 0
(1550 1875);
DISPLAY 0.723404 (1550 1875);
PAINT GREEN (1550 1875);
DISPLAY INVISIBLE (1550 1875);
FORCEADD TAP..1
R 2
(-175 325);
FORCEPROP 3 LASTPIN (-125 325) SIG_NAME M_B_CPU0_SB_CB<6>
J 0
(-115 335);
DISPLAY 0.659574 (-115 335);
PAINT MONO (-115 335);
DISPLAY INVISIBLE (-115 335);
FORCEPROP 1 LASTPIN (-125 325) BN 6
J 2
(-113 333);
DISPLAY 0.680851 (-113 333);
PAINT GREEN (-113 333);
FORCEPROP 2 LAST CDS_LIB standard
J 0
(-175 325);
DISPLAY INVISIBLE (-175 325);
FORCEPROP 1 LAST BODY_TYPE PLUMBING
J 2
(-175 375);
DISPLAY 0.872340 (-175 375);
PAINT GREEN (-175 375);
DISPLAY INVISIBLE (-175 375);
FORCEPROP 1 LAST HDL_TAP TRUE
J 2
(-500 200);
DISPLAY 0.872340 (-500 200);
DISPLAY INVISIBLE (-500 200);
FORCEPROP 1 LAST PATH I17
J 2
(-173 325);
DISPLAY 0.872340 (-173 325);
PAINT GREEN (-173 325);
DISPLAY INVISIBLE (-173 325);
FORCEADD TAP..1
R 2
(-175 375);
FORCEPROP 3 LASTPIN (-125 375) SIG_NAME M_B_CPU0_SB_CB<7>
J 0
(-115 385);
DISPLAY 0.659574 (-115 385);
PAINT MONO (-115 385);
DISPLAY INVISIBLE (-115 385);
FORCEPROP 1 LASTPIN (-125 375) BN 7
J 2
(-113 383);
DISPLAY 0.680851 (-113 383);
PAINT GREEN (-113 383);
FORCEPROP 2 LAST CDS_LIB standard
J 0
(-175 375);
DISPLAY INVISIBLE (-175 375);
FORCEPROP 1 LAST BODY_TYPE PLUMBING
J 2
(-175 425);
DISPLAY 0.872340 (-175 425);
PAINT GREEN (-175 425);
DISPLAY INVISIBLE (-175 425);
FORCEPROP 1 LAST HDL_TAP TRUE
J 2
(-500 250);
DISPLAY 0.872340 (-500 250);
DISPLAY INVISIBLE (-500 250);
FORCEPROP 1 LAST PATH I18
J 2
(-173 375);
DISPLAY 0.872340 (-173 375);
PAINT GREEN (-173 375);
DISPLAY INVISIBLE (-173 375);
FORCEADD TAP..1
R 2
(-175 525);
FORCEPROP 3 LASTPIN (-125 525) SIG_NAME M_B_CPU0_SB_DQ<2>
J 0
(-115 535);
DISPLAY 0.659574 (-115 535);
PAINT MONO (-115 535);
DISPLAY INVISIBLE (-115 535);
FORCEPROP 1 LASTPIN (-125 525) BN 2
J 2
(-113 533);
DISPLAY 0.680851 (-113 533);
PAINT GREEN (-113 533);
FORCEPROP 2 LAST CDS_LIB standard
J 0
(-175 525);
DISPLAY INVISIBLE (-175 525);
FORCEPROP 1 LAST BODY_TYPE PLUMBING
J 2
(-175 575);
DISPLAY 0.872340 (-175 575);
PAINT GREEN (-175 575);
DISPLAY INVISIBLE (-175 575);
FORCEPROP 1 LAST HDL_TAP TRUE
J 2
(-500 400);
DISPLAY 0.872340 (-500 400);
DISPLAY INVISIBLE (-500 400);
FORCEPROP 1 LAST PATH I19
J 2
(-173 525);
DISPLAY 0.872340 (-173 525);
PAINT GREEN (-173 525);
DISPLAY INVISIBLE (-173 525);
FORCEADD TAP..1
R 2
(-175 -225);
FORCEPROP 3 LASTPIN (-125 -225) SIG_NAME M_B_CPU0_CLK_DN<0>
J 0
(-115 -215);
DISPLAY 0.659574 (-115 -215);
PAINT MONO (-115 -215);
DISPLAY INVISIBLE (-115 -215);
FORCEPROP 1 LASTPIN (-125 -225) BN 0
J 2
(-113 -217);
DISPLAY 0.680851 (-113 -217);
PAINT GREEN (-113 -217);
FORCEPROP 2 LAST CDS_LIB standard
J 0
(-175 -225);
DISPLAY INVISIBLE (-175 -225);
FORCEPROP 1 LAST BODY_TYPE PLUMBING
J 2
(-175 -175);
DISPLAY 0.872340 (-175 -175);
PAINT GREEN (-175 -175);
DISPLAY INVISIBLE (-175 -175);
FORCEPROP 1 LAST HDL_TAP TRUE
J 2
(-500 -350);
DISPLAY 0.872340 (-500 -350);
DISPLAY INVISIBLE (-500 -350);
FORCEPROP 1 LAST PATH I2
J 2
(-173 -225);
DISPLAY 0.872340 (-173 -225);
PAINT GREEN (-173 -225);
DISPLAY INVISIBLE (-173 -225);
FORCEADD TAP..1
R 2
(-175 575);
FORCEPROP 3 LASTPIN (-125 575) SIG_NAME M_B_CPU0_SB_DQ<3>
J 0
(-115 585);
DISPLAY 0.659574 (-115 585);
PAINT MONO (-115 585);
DISPLAY INVISIBLE (-115 585);
FORCEPROP 1 LASTPIN (-125 575) BN 3
J 2
(-113 583);
DISPLAY 0.680851 (-113 583);
PAINT GREEN (-113 583);
FORCEPROP 2 LAST CDS_LIB standard
J 0
(-175 575);
DISPLAY INVISIBLE (-175 575);
FORCEPROP 1 LAST BODY_TYPE PLUMBING
J 2
(-175 625);
DISPLAY 0.872340 (-175 625);
PAINT GREEN (-175 625);
DISPLAY INVISIBLE (-175 625);
FORCEPROP 1 LAST HDL_TAP TRUE
J 2
(-500 450);
DISPLAY 0.872340 (-500 450);
DISPLAY INVISIBLE (-500 450);
FORCEPROP 1 LAST PATH I20
J 2
(-173 575);
DISPLAY 0.872340 (-173 575);
PAINT GREEN (-173 575);
DISPLAY INVISIBLE (-173 575);
FORCEADD TAP..1
R 2
(-175 625);
FORCEPROP 3 LASTPIN (-125 625) SIG_NAME M_B_CPU0_SB_DQ<4>
J 0
(-115 635);
DISPLAY 0.659574 (-115 635);
PAINT MONO (-115 635);
DISPLAY INVISIBLE (-115 635);
FORCEPROP 1 LASTPIN (-125 625) BN 4
J 2
(-113 633);
DISPLAY 0.680851 (-113 633);
PAINT GREEN (-113 633);
FORCEPROP 2 LAST CDS_LIB standard
J 0
(-175 625);
DISPLAY INVISIBLE (-175 625);
FORCEPROP 1 LAST BODY_TYPE PLUMBING
J 2
(-175 675);
DISPLAY 0.872340 (-175 675);
PAINT GREEN (-175 675);
DISPLAY INVISIBLE (-175 675);
FORCEPROP 1 LAST HDL_TAP TRUE
J 2
(-500 500);
DISPLAY 0.872340 (-500 500);
DISPLAY INVISIBLE (-500 500);
FORCEPROP 1 LAST PATH I21
J 2
(-173 625);
DISPLAY 0.872340 (-173 625);
PAINT GREEN (-173 625);
DISPLAY INVISIBLE (-173 625);
FORCEADD TAP..1
R 2
(-175 725);
FORCEPROP 3 LASTPIN (-125 725) SIG_NAME M_B_CPU0_SB_DQ<6>
J 0
(-115 735);
DISPLAY 0.659574 (-115 735);
PAINT MONO (-115 735);
DISPLAY INVISIBLE (-115 735);
FORCEPROP 1 LASTPIN (-125 725) BN 6
J 2
(-113 733);
DISPLAY 0.680851 (-113 733);
PAINT GREEN (-113 733);
FORCEPROP 2 LAST CDS_LIB standard
J 0
(-175 725);
DISPLAY INVISIBLE (-175 725);
FORCEPROP 1 LAST BODY_TYPE PLUMBING
J 2
(-175 775);
DISPLAY 0.872340 (-175 775);
PAINT GREEN (-175 775);
DISPLAY INVISIBLE (-175 775);
FORCEPROP 1 LAST HDL_TAP TRUE
J 2
(-500 600);
DISPLAY 0.872340 (-500 600);
DISPLAY INVISIBLE (-500 600);
FORCEPROP 1 LAST PATH I22
J 2
(-173 725);
DISPLAY 0.872340 (-173 725);
PAINT GREEN (-173 725);
DISPLAY INVISIBLE (-173 725);
FORCEADD TAP..1
R 2
(-175 675);
FORCEPROP 3 LASTPIN (-125 675) SIG_NAME M_B_CPU0_SB_DQ<5>
J 0
(-115 685);
DISPLAY 0.659574 (-115 685);
PAINT MONO (-115 685);
DISPLAY INVISIBLE (-115 685);
FORCEPROP 1 LASTPIN (-125 675) BN 5
J 2
(-113 683);
DISPLAY 0.680851 (-113 683);
PAINT GREEN (-113 683);
FORCEPROP 2 LAST CDS_LIB standard
J 0
(-175 675);
DISPLAY INVISIBLE (-175 675);
FORCEPROP 1 LAST BODY_TYPE PLUMBING
J 2
(-175 725);
DISPLAY 0.872340 (-175 725);
PAINT GREEN (-175 725);
DISPLAY INVISIBLE (-175 725);
FORCEPROP 1 LAST HDL_TAP TRUE
J 2
(-500 550);
DISPLAY 0.872340 (-500 550);
DISPLAY INVISIBLE (-500 550);
FORCEPROP 1 LAST PATH I23
J 2
(-173 675);
DISPLAY 0.872340 (-173 675);
PAINT GREEN (-173 675);
DISPLAY INVISIBLE (-173 675);
FORCEADD TAP..1
R 2
(-175 775);
FORCEPROP 3 LASTPIN (-125 775) SIG_NAME M_B_CPU0_SB_DQ<7>
J 0
(-115 785);
DISPLAY 0.659574 (-115 785);
PAINT MONO (-115 785);
DISPLAY INVISIBLE (-115 785);
FORCEPROP 1 LASTPIN (-125 775) BN 7
J 2
(-113 783);
DISPLAY 0.680851 (-113 783);
PAINT GREEN (-113 783);
FORCEPROP 2 LAST CDS_LIB standard
J 0
(-175 775);
DISPLAY INVISIBLE (-175 775);
FORCEPROP 1 LAST BODY_TYPE PLUMBING
J 2
(-175 825);
DISPLAY 0.872340 (-175 825);
PAINT GREEN (-175 825);
DISPLAY INVISIBLE (-175 825);
FORCEPROP 1 LAST HDL_TAP TRUE
J 2
(-500 650);
DISPLAY 0.872340 (-500 650);
DISPLAY INVISIBLE (-500 650);
FORCEPROP 1 LAST PATH I24
J 2
(-173 775);
DISPLAY 0.872340 (-173 775);
PAINT GREEN (-173 775);
DISPLAY INVISIBLE (-173 775);
FORCEADD TAP..1
R 2
(-175 825);
FORCEPROP 3 LASTPIN (-125 825) SIG_NAME M_B_CPU0_SB_DQ<8>
J 0
(-115 835);
DISPLAY 0.659574 (-115 835);
PAINT MONO (-115 835);
DISPLAY INVISIBLE (-115 835);
FORCEPROP 1 LASTPIN (-125 825) BN 8
J 2
(-113 833);
DISPLAY 0.680851 (-113 833);
PAINT GREEN (-113 833);
FORCEPROP 2 LAST CDS_LIB standard
J 0
(-175 825);
DISPLAY INVISIBLE (-175 825);
FORCEPROP 1 LAST BODY_TYPE PLUMBING
J 2
(-175 875);
DISPLAY 0.872340 (-175 875);
PAINT GREEN (-175 875);
DISPLAY INVISIBLE (-175 875);
FORCEPROP 1 LAST HDL_TAP TRUE
J 2
(-500 700);
DISPLAY 0.872340 (-500 700);
DISPLAY INVISIBLE (-500 700);
FORCEPROP 1 LAST PATH I25
J 2
(-173 825);
DISPLAY 0.872340 (-173 825);
PAINT GREEN (-173 825);
DISPLAY INVISIBLE (-173 825);
FORCEADD TAP..1
R 2
(-175 875);
FORCEPROP 3 LASTPIN (-125 875) SIG_NAME M_B_CPU0_SB_DQ<9>
J 0
(-115 885);
DISPLAY 0.659574 (-115 885);
PAINT MONO (-115 885);
DISPLAY INVISIBLE (-115 885);
FORCEPROP 1 LASTPIN (-125 875) BN 9
J 2
(-113 883);
DISPLAY 0.680851 (-113 883);
PAINT GREEN (-113 883);
FORCEPROP 2 LAST CDS_LIB standard
J 0
(-175 875);
DISPLAY INVISIBLE (-175 875);
FORCEPROP 1 LAST BODY_TYPE PLUMBING
J 2
(-175 925);
DISPLAY 0.872340 (-175 925);
PAINT GREEN (-175 925);
DISPLAY INVISIBLE (-175 925);
FORCEPROP 1 LAST HDL_TAP TRUE
J 2
(-500 750);
DISPLAY 0.872340 (-500 750);
DISPLAY INVISIBLE (-500 750);
FORCEPROP 1 LAST PATH I26
J 2
(-173 875);
DISPLAY 0.872340 (-173 875);
PAINT GREEN (-173 875);
DISPLAY INVISIBLE (-173 875);
FORCEADD TAP..1
R 2
(-175 925);
FORCEPROP 3 LASTPIN (-125 925) SIG_NAME M_B_CPU0_SB_DQ<10>
J 0
(-115 935);
DISPLAY 0.659574 (-115 935);
PAINT MONO (-115 935);
DISPLAY INVISIBLE (-115 935);
FORCEPROP 1 LASTPIN (-125 925) BN 10
J 2
(-113 933);
DISPLAY 0.680851 (-113 933);
PAINT GREEN (-113 933);
FORCEPROP 2 LAST CDS_LIB standard
J 0
(-175 925);
DISPLAY INVISIBLE (-175 925);
FORCEPROP 1 LAST BODY_TYPE PLUMBING
J 2
(-175 975);
DISPLAY 0.872340 (-175 975);
PAINT GREEN (-175 975);
DISPLAY INVISIBLE (-175 975);
FORCEPROP 1 LAST HDL_TAP TRUE
J 2
(-500 800);
DISPLAY 0.872340 (-500 800);
DISPLAY INVISIBLE (-500 800);
FORCEPROP 1 LAST PATH I27
J 2
(-173 925);
DISPLAY 0.872340 (-173 925);
PAINT GREEN (-173 925);
DISPLAY INVISIBLE (-173 925);
FORCEADD TAP..1
R 2
(-175 1025);
FORCEPROP 3 LASTPIN (-125 1025) SIG_NAME M_B_CPU0_SB_DQ<12>
J 0
(-115 1035);
DISPLAY 0.659574 (-115 1035);
PAINT MONO (-115 1035);
DISPLAY INVISIBLE (-115 1035);
FORCEPROP 1 LASTPIN (-125 1025) BN 12
J 2
(-113 1033);
DISPLAY 0.680851 (-113 1033);
PAINT GREEN (-113 1033);
FORCEPROP 2 LAST CDS_LIB standard
J 0
(-175 1025);
DISPLAY INVISIBLE (-175 1025);
FORCEPROP 1 LAST BODY_TYPE PLUMBING
J 2
(-175 1075);
DISPLAY 0.872340 (-175 1075);
PAINT GREEN (-175 1075);
DISPLAY INVISIBLE (-175 1075);
FORCEPROP 1 LAST HDL_TAP TRUE
J 2
(-500 900);
DISPLAY 0.872340 (-500 900);
DISPLAY INVISIBLE (-500 900);
FORCEPROP 1 LAST PATH I28
J 2
(-173 1025);
DISPLAY 0.872340 (-173 1025);
PAINT GREEN (-173 1025);
DISPLAY INVISIBLE (-173 1025);
FORCEADD TAP..1
R 2
(-175 975);
FORCEPROP 3 LASTPIN (-125 975) SIG_NAME M_B_CPU0_SB_DQ<11>
J 0
(-115 985);
DISPLAY 0.659574 (-115 985);
PAINT MONO (-115 985);
DISPLAY INVISIBLE (-115 985);
FORCEPROP 1 LASTPIN (-125 975) BN 11
J 2
(-113 983);
DISPLAY 0.680851 (-113 983);
PAINT GREEN (-113 983);
FORCEPROP 2 LAST CDS_LIB standard
J 0
(-175 975);
DISPLAY INVISIBLE (-175 975);
FORCEPROP 1 LAST BODY_TYPE PLUMBING
J 2
(-175 1025);
DISPLAY 0.872340 (-175 1025);
PAINT GREEN (-175 1025);
DISPLAY INVISIBLE (-175 1025);
FORCEPROP 1 LAST HDL_TAP TRUE
J 2
(-500 850);
DISPLAY 0.872340 (-500 850);
DISPLAY INVISIBLE (-500 850);
FORCEPROP 1 LAST PATH I29
J 2
(-173 975);
DISPLAY 0.872340 (-173 975);
PAINT GREEN (-173 975);
DISPLAY INVISIBLE (-173 975);
FORCEADD OFFPAGE..2
R 2
(-1200 -150);
FORCEPROP 2 LAST $XR1 85 
J 0
(-1544 -150);
DISPLAY 0.638298 (-1544 -150);
PAINT MONO (-1544 -150);
FORCEPROP 2 LAST $XR0 84 
J 0
(-1454 -150);
DISPLAY 0.638298 (-1454 -150);
PAINT MONO (-1454 -150);
FORCEPROP 2 LAST CDS_LIB standard
J 0
(-1200 -150);
PAINT MONO (-1200 -150);
DISPLAY INVISIBLE (-1200 -150);
FORCEPROP 1 LAST OFFPAGE TRUE
J 2
(-1525 -275);
DISPLAY 0.872340 (-1525 -275);
DISPLAY INVISIBLE (-1525 -275);
FORCEPROP 1 LAST COMMENT_BODY TRUE
J 2
(-1155 -245);
DISPLAY 0.872340 (-1155 -245);
PAINT GREEN (-1155 -245);
DISPLAY INVISIBLE (-1155 -245);
FORCEPROP 2 LAST PATH I3
J 0
(-1150 -75);
DISPLAY 1.021277 (-1150 -75);
DISPLAY INVISIBLE (-1150 -75);
FORCEADD TAP..1
R 2
(-175 1075);
FORCEPROP 3 LASTPIN (-125 1075) SIG_NAME M_B_CPU0_SB_DQ<13>
J 0
(-115 1085);
DISPLAY 0.659574 (-115 1085);
PAINT MONO (-115 1085);
DISPLAY INVISIBLE (-115 1085);
FORCEPROP 1 LASTPIN (-125 1075) BN 13
J 2
(-113 1083);
DISPLAY 0.680851 (-113 1083);
PAINT GREEN (-113 1083);
FORCEPROP 2 LAST CDS_LIB standard
J 0
(-175 1075);
DISPLAY INVISIBLE (-175 1075);
FORCEPROP 1 LAST BODY_TYPE PLUMBING
J 2
(-175 1125);
DISPLAY 0.872340 (-175 1125);
PAINT GREEN (-175 1125);
DISPLAY INVISIBLE (-175 1125);
FORCEPROP 1 LAST HDL_TAP TRUE
J 2
(-500 950);
DISPLAY 0.872340 (-500 950);
DISPLAY INVISIBLE (-500 950);
FORCEPROP 1 LAST PATH I30
J 2
(-173 1075);
DISPLAY 0.872340 (-173 1075);
PAINT GREEN (-173 1075);
DISPLAY INVISIBLE (-173 1075);
FORCEADD TAP..1
R 2
(-175 1125);
FORCEPROP 3 LASTPIN (-125 1125) SIG_NAME M_B_CPU0_SB_DQ<14>
J 0
(-115 1135);
DISPLAY 0.659574 (-115 1135);
PAINT MONO (-115 1135);
DISPLAY INVISIBLE (-115 1135);
FORCEPROP 1 LASTPIN (-125 1125) BN 14
J 2
(-113 1133);
DISPLAY 0.680851 (-113 1133);
PAINT GREEN (-113 1133);
FORCEPROP 2 LAST CDS_LIB standard
J 0
(-175 1125);
DISPLAY INVISIBLE (-175 1125);
FORCEPROP 1 LAST BODY_TYPE PLUMBING
J 2
(-175 1175);
DISPLAY 0.872340 (-175 1175);
PAINT GREEN (-175 1175);
DISPLAY INVISIBLE (-175 1175);
FORCEPROP 1 LAST HDL_TAP TRUE
J 2
(-500 1000);
DISPLAY 0.872340 (-500 1000);
DISPLAY INVISIBLE (-500 1000);
FORCEPROP 1 LAST PATH I31
J 2
(-173 1125);
DISPLAY 0.872340 (-173 1125);
PAINT GREEN (-173 1125);
DISPLAY INVISIBLE (-173 1125);
FORCEADD TAP..1
R 2
(-175 1175);
FORCEPROP 3 LASTPIN (-125 1175) SIG_NAME M_B_CPU0_SB_DQ<15>
J 0
(-115 1185);
DISPLAY 0.659574 (-115 1185);
PAINT MONO (-115 1185);
DISPLAY INVISIBLE (-115 1185);
FORCEPROP 1 LASTPIN (-125 1175) BN 15
J 2
(-113 1183);
DISPLAY 0.680851 (-113 1183);
PAINT GREEN (-113 1183);
FORCEPROP 2 LAST CDS_LIB standard
J 0
(-175 1175);
DISPLAY INVISIBLE (-175 1175);
FORCEPROP 1 LAST BODY_TYPE PLUMBING
J 2
(-175 1225);
DISPLAY 0.872340 (-175 1225);
PAINT GREEN (-175 1225);
DISPLAY INVISIBLE (-175 1225);
FORCEPROP 1 LAST HDL_TAP TRUE
J 2
(-500 1050);
DISPLAY 0.872340 (-500 1050);
DISPLAY INVISIBLE (-500 1050);
FORCEPROP 1 LAST PATH I32
J 2
(-173 1175);
DISPLAY 0.872340 (-173 1175);
PAINT GREEN (-173 1175);
DISPLAY INVISIBLE (-173 1175);
FORCEADD TAP..1
R 2
(-175 1225);
FORCEPROP 3 LASTPIN (-125 1225) SIG_NAME M_B_CPU0_SB_DQ<16>
J 0
(-115 1235);
DISPLAY 0.659574 (-115 1235);
PAINT MONO (-115 1235);
DISPLAY INVISIBLE (-115 1235);
FORCEPROP 1 LASTPIN (-125 1225) BN 16
J 2
(-113 1233);
DISPLAY 0.680851 (-113 1233);
PAINT GREEN (-113 1233);
FORCEPROP 2 LAST CDS_LIB standard
J 0
(-175 1225);
DISPLAY INVISIBLE (-175 1225);
FORCEPROP 1 LAST BODY_TYPE PLUMBING
J 2
(-175 1275);
DISPLAY 0.872340 (-175 1275);
PAINT GREEN (-175 1275);
DISPLAY INVISIBLE (-175 1275);
FORCEPROP 1 LAST HDL_TAP TRUE
J 2
(-500 1100);
DISPLAY 0.872340 (-500 1100);
DISPLAY INVISIBLE (-500 1100);
FORCEPROP 1 LAST PATH I33
J 2
(-173 1225);
DISPLAY 0.872340 (-173 1225);
PAINT GREEN (-173 1225);
DISPLAY INVISIBLE (-173 1225);
FORCEADD TAP..1
R 2
(-175 1275);
FORCEPROP 3 LASTPIN (-125 1275) SIG_NAME M_B_CPU0_SB_DQ<17>
J 0
(-115 1285);
DISPLAY 0.659574 (-115 1285);
PAINT MONO (-115 1285);
DISPLAY INVISIBLE (-115 1285);
FORCEPROP 1 LASTPIN (-125 1275) BN 17
J 2
(-113 1283);
DISPLAY 0.680851 (-113 1283);
PAINT GREEN (-113 1283);
FORCEPROP 2 LAST CDS_LIB standard
J 0
(-175 1275);
DISPLAY INVISIBLE (-175 1275);
FORCEPROP 1 LAST BODY_TYPE PLUMBING
J 2
(-175 1325);
DISPLAY 0.872340 (-175 1325);
PAINT GREEN (-175 1325);
DISPLAY INVISIBLE (-175 1325);
FORCEPROP 1 LAST HDL_TAP TRUE
J 2
(-500 1150);
DISPLAY 0.872340 (-500 1150);
DISPLAY INVISIBLE (-500 1150);
FORCEPROP 1 LAST PATH I34
J 2
(-173 1275);
DISPLAY 0.872340 (-173 1275);
PAINT GREEN (-173 1275);
DISPLAY INVISIBLE (-173 1275);
FORCEADD TAP..1
R 2
(-175 1325);
FORCEPROP 3 LASTPIN (-125 1325) SIG_NAME M_B_CPU0_SB_DQ<18>
J 0
(-115 1335);
DISPLAY 0.659574 (-115 1335);
PAINT MONO (-115 1335);
DISPLAY INVISIBLE (-115 1335);
FORCEPROP 1 LASTPIN (-125 1325) BN 18
J 2
(-113 1333);
DISPLAY 0.680851 (-113 1333);
PAINT GREEN (-113 1333);
FORCEPROP 2 LAST CDS_LIB standard
J 0
(-175 1325);
DISPLAY INVISIBLE (-175 1325);
FORCEPROP 1 LAST BODY_TYPE PLUMBING
J 2
(-175 1375);
DISPLAY 0.872340 (-175 1375);
PAINT GREEN (-175 1375);
DISPLAY INVISIBLE (-175 1375);
FORCEPROP 1 LAST HDL_TAP TRUE
J 2
(-500 1200);
DISPLAY 0.872340 (-500 1200);
DISPLAY INVISIBLE (-500 1200);
FORCEPROP 1 LAST PATH I35
J 2
(-173 1325);
DISPLAY 0.872340 (-173 1325);
PAINT GREEN (-173 1325);
DISPLAY INVISIBLE (-173 1325);
FORCEADD TAP..1
R 2
(-175 1375);
FORCEPROP 3 LASTPIN (-125 1375) SIG_NAME M_B_CPU0_SB_DQ<19>
J 0
(-115 1385);
DISPLAY 0.659574 (-115 1385);
PAINT MONO (-115 1385);
DISPLAY INVISIBLE (-115 1385);
FORCEPROP 1 LASTPIN (-125 1375) BN 19
J 2
(-113 1383);
DISPLAY 0.680851 (-113 1383);
PAINT GREEN (-113 1383);
FORCEPROP 2 LAST CDS_LIB standard
J 0
(-175 1375);
DISPLAY INVISIBLE (-175 1375);
FORCEPROP 1 LAST BODY_TYPE PLUMBING
J 2
(-175 1425);
DISPLAY 0.872340 (-175 1425);
PAINT GREEN (-175 1425);
DISPLAY INVISIBLE (-175 1425);
FORCEPROP 1 LAST HDL_TAP TRUE
J 2
(-500 1250);
DISPLAY 0.872340 (-500 1250);
DISPLAY INVISIBLE (-500 1250);
FORCEPROP 1 LAST PATH I36
J 2
(-173 1375);
DISPLAY 0.872340 (-173 1375);
PAINT GREEN (-173 1375);
DISPLAY INVISIBLE (-173 1375);
FORCEADD TAP..1
R 2
(-175 1425);
FORCEPROP 3 LASTPIN (-125 1425) SIG_NAME M_B_CPU0_SB_DQ<20>
J 0
(-115 1435);
DISPLAY 0.659574 (-115 1435);
PAINT MONO (-115 1435);
DISPLAY INVISIBLE (-115 1435);
FORCEPROP 1 LASTPIN (-125 1425) BN 20
J 2
(-113 1433);
DISPLAY 0.680851 (-113 1433);
PAINT GREEN (-113 1433);
FORCEPROP 2 LAST CDS_LIB standard
J 0
(-175 1425);
DISPLAY INVISIBLE (-175 1425);
FORCEPROP 1 LAST BODY_TYPE PLUMBING
J 2
(-175 1475);
DISPLAY 0.872340 (-175 1475);
PAINT GREEN (-175 1475);
DISPLAY INVISIBLE (-175 1475);
FORCEPROP 1 LAST HDL_TAP TRUE
J 2
(-500 1300);
DISPLAY 0.872340 (-500 1300);
DISPLAY INVISIBLE (-500 1300);
FORCEPROP 1 LAST PATH I37
J 2
(-173 1425);
DISPLAY 0.872340 (-173 1425);
PAINT GREEN (-173 1425);
DISPLAY INVISIBLE (-173 1425);
FORCEADD TAP..1
R 2
(-175 1475);
FORCEPROP 3 LASTPIN (-125 1475) SIG_NAME M_B_CPU0_SB_DQ<21>
J 0
(-115 1485);
DISPLAY 0.659574 (-115 1485);
PAINT MONO (-115 1485);
DISPLAY INVISIBLE (-115 1485);
FORCEPROP 1 LASTPIN (-125 1475) BN 21
J 2
(-113 1483);
DISPLAY 0.680851 (-113 1483);
PAINT GREEN (-113 1483);
FORCEPROP 2 LAST CDS_LIB standard
J 0
(-175 1475);
DISPLAY INVISIBLE (-175 1475);
FORCEPROP 1 LAST BODY_TYPE PLUMBING
J 2
(-175 1525);
DISPLAY 0.872340 (-175 1525);
PAINT GREEN (-175 1525);
DISPLAY INVISIBLE (-175 1525);
FORCEPROP 1 LAST HDL_TAP TRUE
J 2
(-500 1350);
DISPLAY 0.872340 (-500 1350);
DISPLAY INVISIBLE (-500 1350);
FORCEPROP 1 LAST PATH I38
J 2
(-173 1475);
DISPLAY 0.872340 (-173 1475);
PAINT GREEN (-173 1475);
DISPLAY INVISIBLE (-173 1475);
FORCEADD TAP..1
R 2
(-175 1525);
FORCEPROP 3 LASTPIN (-125 1525) SIG_NAME M_B_CPU0_SB_DQ<22>
J 0
(-115 1535);
DISPLAY 0.659574 (-115 1535);
PAINT MONO (-115 1535);
DISPLAY INVISIBLE (-115 1535);
FORCEPROP 1 LASTPIN (-125 1525) BN 22
J 2
(-113 1533);
DISPLAY 0.680851 (-113 1533);
PAINT GREEN (-113 1533);
FORCEPROP 2 LAST CDS_LIB standard
J 0
(-175 1525);
DISPLAY INVISIBLE (-175 1525);
FORCEPROP 1 LAST BODY_TYPE PLUMBING
J 2
(-175 1575);
DISPLAY 0.872340 (-175 1575);
PAINT GREEN (-175 1575);
DISPLAY INVISIBLE (-175 1575);
FORCEPROP 1 LAST HDL_TAP TRUE
J 2
(-500 1400);
DISPLAY 0.872340 (-500 1400);
DISPLAY INVISIBLE (-500 1400);
FORCEPROP 1 LAST PATH I39
J 2
(-173 1525);
DISPLAY 0.872340 (-173 1525);
PAINT GREEN (-173 1525);
DISPLAY INVISIBLE (-173 1525);
FORCEADD OFFPAGE..2
R 2
(-1200 -50);
FORCEPROP 2 LAST $XR1 85 
J 0
(-1544 -50);
DISPLAY 0.638298 (-1544 -50);
PAINT MONO (-1544 -50);
FORCEPROP 2 LAST $XR0 84 
J 0
(-1454 -50);
DISPLAY 0.638298 (-1454 -50);
PAINT MONO (-1454 -50);
FORCEPROP 2 LAST CDS_LIB standard
J 0
(-1200 -50);
PAINT MONO (-1200 -50);
DISPLAY INVISIBLE (-1200 -50);
FORCEPROP 1 LAST OFFPAGE TRUE
J 2
(-1525 -175);
DISPLAY 0.872340 (-1525 -175);
DISPLAY INVISIBLE (-1525 -175);
FORCEPROP 1 LAST COMMENT_BODY TRUE
J 2
(-1155 -145);
DISPLAY 0.872340 (-1155 -145);
PAINT GREEN (-1155 -145);
DISPLAY INVISIBLE (-1155 -145);
FORCEPROP 2 LAST PATH I4
J 0
(-1150 25);
DISPLAY 1.021277 (-1150 25);
DISPLAY INVISIBLE (-1150 25);
FORCEADD TAP..1
R 2
(-175 1575);
FORCEPROP 3 LASTPIN (-125 1575) SIG_NAME M_B_CPU0_SB_DQ<23>
J 0
(-115 1585);
DISPLAY 0.659574 (-115 1585);
PAINT MONO (-115 1585);
DISPLAY INVISIBLE (-115 1585);
FORCEPROP 1 LASTPIN (-125 1575) BN 23
J 2
(-113 1583);
DISPLAY 0.680851 (-113 1583);
PAINT GREEN (-113 1583);
FORCEPROP 2 LAST CDS_LIB standard
J 0
(-175 1575);
DISPLAY INVISIBLE (-175 1575);
FORCEPROP 1 LAST BODY_TYPE PLUMBING
J 2
(-175 1625);
DISPLAY 0.872340 (-175 1625);
PAINT GREEN (-175 1625);
DISPLAY INVISIBLE (-175 1625);
FORCEPROP 1 LAST HDL_TAP TRUE
J 2
(-500 1450);
DISPLAY 0.872340 (-500 1450);
DISPLAY INVISIBLE (-500 1450);
FORCEPROP 1 LAST PATH I40
J 2
(-173 1575);
DISPLAY 0.872340 (-173 1575);
PAINT GREEN (-173 1575);
DISPLAY INVISIBLE (-173 1575);
FORCEADD TAP..1
R 2
(-175 1625);
FORCEPROP 3 LASTPIN (-125 1625) SIG_NAME M_B_CPU0_SB_DQ<24>
J 0
(-115 1635);
DISPLAY 0.659574 (-115 1635);
PAINT MONO (-115 1635);
DISPLAY INVISIBLE (-115 1635);
FORCEPROP 1 LASTPIN (-125 1625) BN 24
J 2
(-113 1633);
DISPLAY 0.680851 (-113 1633);
PAINT GREEN (-113 1633);
FORCEPROP 2 LAST CDS_LIB standard
J 0
(-175 1625);
DISPLAY INVISIBLE (-175 1625);
FORCEPROP 1 LAST BODY_TYPE PLUMBING
J 2
(-175 1675);
DISPLAY 0.872340 (-175 1675);
PAINT GREEN (-175 1675);
DISPLAY INVISIBLE (-175 1675);
FORCEPROP 1 LAST HDL_TAP TRUE
J 2
(-500 1500);
DISPLAY 0.872340 (-500 1500);
DISPLAY INVISIBLE (-500 1500);
FORCEPROP 1 LAST PATH I41
J 2
(-173 1625);
DISPLAY 0.872340 (-173 1625);
PAINT GREEN (-173 1625);
DISPLAY INVISIBLE (-173 1625);
FORCEADD TAP..1
R 2
(-175 1675);
FORCEPROP 3 LASTPIN (-125 1675) SIG_NAME M_B_CPU0_SB_DQ<25>
J 0
(-115 1685);
DISPLAY 0.659574 (-115 1685);
PAINT MONO (-115 1685);
DISPLAY INVISIBLE (-115 1685);
FORCEPROP 1 LASTPIN (-125 1675) BN 25
J 2
(-113 1683);
DISPLAY 0.680851 (-113 1683);
PAINT GREEN (-113 1683);
FORCEPROP 2 LAST CDS_LIB standard
J 0
(-175 1675);
DISPLAY INVISIBLE (-175 1675);
FORCEPROP 1 LAST BODY_TYPE PLUMBING
J 2
(-175 1725);
DISPLAY 0.872340 (-175 1725);
PAINT GREEN (-175 1725);
DISPLAY INVISIBLE (-175 1725);
FORCEPROP 1 LAST HDL_TAP TRUE
J 2
(-500 1550);
DISPLAY 0.872340 (-500 1550);
DISPLAY INVISIBLE (-500 1550);
FORCEPROP 1 LAST PATH I42
J 2
(-173 1675);
DISPLAY 0.872340 (-173 1675);
PAINT GREEN (-173 1675);
DISPLAY INVISIBLE (-173 1675);
FORCEADD TAP..1
R 2
(-175 1725);
FORCEPROP 3 LASTPIN (-125 1725) SIG_NAME M_B_CPU0_SB_DQ<26>
J 0
(-115 1735);
DISPLAY 0.659574 (-115 1735);
PAINT MONO (-115 1735);
DISPLAY INVISIBLE (-115 1735);
FORCEPROP 1 LASTPIN (-125 1725) BN 26
J 2
(-113 1733);
DISPLAY 0.680851 (-113 1733);
PAINT GREEN (-113 1733);
FORCEPROP 2 LAST CDS_LIB standard
J 0
(-175 1725);
DISPLAY INVISIBLE (-175 1725);
FORCEPROP 1 LAST BODY_TYPE PLUMBING
J 2
(-175 1775);
DISPLAY 0.872340 (-175 1775);
PAINT GREEN (-175 1775);
DISPLAY INVISIBLE (-175 1775);
FORCEPROP 1 LAST HDL_TAP TRUE
J 2
(-500 1600);
DISPLAY 0.872340 (-500 1600);
DISPLAY INVISIBLE (-500 1600);
FORCEPROP 1 LAST PATH I43
J 2
(-173 1725);
DISPLAY 0.872340 (-173 1725);
PAINT GREEN (-173 1725);
DISPLAY INVISIBLE (-173 1725);
FORCEADD TAP..1
R 2
(-175 1775);
FORCEPROP 3 LASTPIN (-125 1775) SIG_NAME M_B_CPU0_SB_DQ<27>
J 0
(-115 1785);
DISPLAY 0.659574 (-115 1785);
PAINT MONO (-115 1785);
DISPLAY INVISIBLE (-115 1785);
FORCEPROP 1 LASTPIN (-125 1775) BN 27
J 2
(-113 1783);
DISPLAY 0.680851 (-113 1783);
PAINT GREEN (-113 1783);
FORCEPROP 2 LAST CDS_LIB standard
J 0
(-175 1775);
DISPLAY INVISIBLE (-175 1775);
FORCEPROP 1 LAST BODY_TYPE PLUMBING
J 2
(-175 1825);
DISPLAY 0.872340 (-175 1825);
PAINT GREEN (-175 1825);
DISPLAY INVISIBLE (-175 1825);
FORCEPROP 1 LAST HDL_TAP TRUE
J 2
(-500 1650);
DISPLAY 0.872340 (-500 1650);
DISPLAY INVISIBLE (-500 1650);
FORCEPROP 1 LAST PATH I44
J 2
(-173 1775);
DISPLAY 0.872340 (-173 1775);
PAINT GREEN (-173 1775);
DISPLAY INVISIBLE (-173 1775);
FORCEADD OFFPAGE..3
R 2
(-1200 2000);
FORCEPROP 2 LAST $XR1 85 
J 0
(-1569 2000);
DISPLAY 0.638298 (-1569 2000);
PAINT MONO (-1569 2000);
FORCEPROP 2 LAST $XR0 84 
J 0
(-1479 2000);
DISPLAY 0.638298 (-1479 2000);
PAINT MONO (-1479 2000);
FORCEPROP 2 LAST CDS_LIB standard
J 0
(-1200 2000);
DISPLAY INVISIBLE (-1200 2000);
FORCEPROP 1 LAST OFFPAGE TRUE
J 2
(-1525 1875);
DISPLAY 0.872340 (-1525 1875);
DISPLAY INVISIBLE (-1525 1875);
FORCEPROP 1 LAST COMMENT_BODY TRUE
J 2
(-1150 1900);
DISPLAY 0.872340 (-1150 1900);
PAINT GREEN (-1150 1900);
DISPLAY INVISIBLE (-1150 1900);
FORCEPROP 2 LAST PATH I45
J 0
(-1150 2075);
DISPLAY 1.021277 (-1150 2075);
DISPLAY INVISIBLE (-1150 2075);
FORCEADD OFFPAGE..3
R 2
(-1200 2400);
FORCEPROP 2 LAST $XR1 85 
J 0
(-1569 2400);
DISPLAY 0.638298 (-1569 2400);
PAINT MONO (-1569 2400);
FORCEPROP 2 LAST $XR0 84 
J 0
(-1479 2400);
DISPLAY 0.638298 (-1479 2400);
PAINT MONO (-1479 2400);
FORCEPROP 2 LAST CDS_LIB standard
J 0
(-1200 2400);
DISPLAY INVISIBLE (-1200 2400);
FORCEPROP 1 LAST OFFPAGE TRUE
J 2
(-1525 2275);
DISPLAY 0.872340 (-1525 2275);
DISPLAY INVISIBLE (-1525 2275);
FORCEPROP 1 LAST COMMENT_BODY TRUE
J 2
(-1150 2300);
DISPLAY 0.872340 (-1150 2300);
PAINT GREEN (-1150 2300);
DISPLAY INVISIBLE (-1150 2300);
FORCEPROP 2 LAST PATH I46
J 0
(-1150 2475);
DISPLAY 1.021277 (-1150 2475);
DISPLAY INVISIBLE (-1150 2475);
FORCEADD TAP..1
R 2
(-175 1875);
FORCEPROP 3 LASTPIN (-125 1875) SIG_NAME M_B_CPU0_SB_DQ<29>
J 0
(-115 1885);
DISPLAY 0.659574 (-115 1885);
PAINT MONO (-115 1885);
DISPLAY INVISIBLE (-115 1885);
FORCEPROP 1 LASTPIN (-125 1875) BN 29
J 2
(-113 1883);
DISPLAY 0.680851 (-113 1883);
PAINT GREEN (-113 1883);
FORCEPROP 2 LAST CDS_LIB standard
J 0
(-175 1875);
DISPLAY INVISIBLE (-175 1875);
FORCEPROP 1 LAST BODY_TYPE PLUMBING
J 2
(-175 1925);
DISPLAY 0.872340 (-175 1925);
PAINT GREEN (-175 1925);
DISPLAY INVISIBLE (-175 1925);
FORCEPROP 1 LAST HDL_TAP TRUE
J 2
(-500 1750);
DISPLAY 0.872340 (-500 1750);
DISPLAY INVISIBLE (-500 1750);
FORCEPROP 1 LAST PATH I47
J 2
(-173 1875);
DISPLAY 0.872340 (-173 1875);
PAINT GREEN (-173 1875);
DISPLAY INVISIBLE (-173 1875);
FORCEADD TAP..1
R 2
(-175 1925);
FORCEPROP 3 LASTPIN (-125 1925) SIG_NAME M_B_CPU0_SB_DQ<30>
J 0
(-115 1935);
DISPLAY 0.659574 (-115 1935);
PAINT MONO (-115 1935);
DISPLAY INVISIBLE (-115 1935);
FORCEPROP 1 LASTPIN (-125 1925) BN 30
J 2
(-113 1933);
DISPLAY 0.680851 (-113 1933);
PAINT GREEN (-113 1933);
FORCEPROP 2 LAST CDS_LIB standard
J 0
(-175 1925);
DISPLAY INVISIBLE (-175 1925);
FORCEPROP 1 LAST BODY_TYPE PLUMBING
J 2
(-175 1975);
DISPLAY 0.872340 (-175 1975);
PAINT GREEN (-175 1975);
DISPLAY INVISIBLE (-175 1975);
FORCEPROP 1 LAST HDL_TAP TRUE
J 2
(-500 1800);
DISPLAY 0.872340 (-500 1800);
DISPLAY INVISIBLE (-500 1800);
FORCEPROP 1 LAST PATH I48
J 2
(-173 1925);
DISPLAY 0.872340 (-173 1925);
PAINT GREEN (-173 1925);
DISPLAY INVISIBLE (-173 1925);
FORCEADD TAP..1
R 2
(-175 1825);
FORCEPROP 3 LASTPIN (-125 1825) SIG_NAME M_B_CPU0_SB_DQ<28>
J 0
(-115 1835);
DISPLAY 0.659574 (-115 1835);
PAINT MONO (-115 1835);
DISPLAY INVISIBLE (-115 1835);
FORCEPROP 1 LASTPIN (-125 1825) BN 28
J 2
(-113 1833);
DISPLAY 0.680851 (-113 1833);
PAINT GREEN (-113 1833);
FORCEPROP 2 LAST CDS_LIB standard
J 0
(-175 1825);
DISPLAY INVISIBLE (-175 1825);
FORCEPROP 1 LAST BODY_TYPE PLUMBING
J 2
(-175 1875);
DISPLAY 0.872340 (-175 1875);
PAINT GREEN (-175 1875);
DISPLAY INVISIBLE (-175 1875);
FORCEPROP 1 LAST HDL_TAP TRUE
J 2
(-500 1700);
DISPLAY 0.872340 (-500 1700);
DISPLAY INVISIBLE (-500 1700);
FORCEPROP 1 LAST PATH I49
J 2
(-173 1825);
DISPLAY 0.872340 (-173 1825);
PAINT GREEN (-173 1825);
DISPLAY INVISIBLE (-173 1825);
FORCEADD OFFPAGE..3
R 2
(-1200 400);
FORCEPROP 2 LAST $XR1 85 
J 0
(-1569 400);
DISPLAY 0.638298 (-1569 400);
PAINT MONO (-1569 400);
FORCEPROP 2 LAST $XR0 84 
J 0
(-1479 400);
DISPLAY 0.638298 (-1479 400);
PAINT MONO (-1479 400);
FORCEPROP 2 LAST CDS_LIB standard
J 0
(-1200 400);
DISPLAY INVISIBLE (-1200 400);
FORCEPROP 1 LAST OFFPAGE TRUE
J 2
(-1525 275);
DISPLAY 0.872340 (-1525 275);
DISPLAY INVISIBLE (-1525 275);
FORCEPROP 1 LAST COMMENT_BODY TRUE
J 2
(-1150 300);
DISPLAY 0.872340 (-1150 300);
PAINT GREEN (-1150 300);
DISPLAY INVISIBLE (-1150 300);
FORCEPROP 2 LAST PATH I5
J 0
(-1150 475);
DISPLAY 1.021277 (-1150 475);
DISPLAY INVISIBLE (-1150 475);
FORCEADD TAP..1
R 2
(-175 2025);
FORCEPROP 3 LASTPIN (-125 2025) SIG_NAME M_B_CPU0_SA_CB<0>
J 0
(-115 2035);
DISPLAY 0.659574 (-115 2035);
PAINT MONO (-115 2035);
DISPLAY INVISIBLE (-115 2035);
FORCEPROP 1 LASTPIN (-125 2025) BN 0
J 2
(-113 2033);
DISPLAY 0.680851 (-113 2033);
PAINT GREEN (-113 2033);
FORCEPROP 2 LAST CDS_LIB standard
J 0
(-175 2025);
DISPLAY INVISIBLE (-175 2025);
FORCEPROP 1 LAST BODY_TYPE PLUMBING
J 2
(-175 2075);
DISPLAY 0.872340 (-175 2075);
PAINT GREEN (-175 2075);
DISPLAY INVISIBLE (-175 2075);
FORCEPROP 1 LAST HDL_TAP TRUE
J 2
(-500 1900);
DISPLAY 0.872340 (-500 1900);
DISPLAY INVISIBLE (-500 1900);
FORCEPROP 1 LAST PATH I50
J 2
(-173 2025);
DISPLAY 0.872340 (-173 2025);
PAINT GREEN (-173 2025);
DISPLAY INVISIBLE (-173 2025);
FORCEADD TAP..1
R 2
(-175 1975);
FORCEPROP 3 LASTPIN (-125 1975) SIG_NAME M_B_CPU0_SB_DQ<31>
J 0
(-115 1985);
DISPLAY 0.659574 (-115 1985);
PAINT MONO (-115 1985);
DISPLAY INVISIBLE (-115 1985);
FORCEPROP 1 LASTPIN (-125 1975) BN 31
J 2
(-113 1983);
DISPLAY 0.680851 (-113 1983);
PAINT GREEN (-113 1983);
FORCEPROP 2 LAST CDS_LIB standard
J 0
(-175 1975);
DISPLAY INVISIBLE (-175 1975);
FORCEPROP 1 LAST BODY_TYPE PLUMBING
J 2
(-175 2025);
DISPLAY 0.872340 (-175 2025);
PAINT GREEN (-175 2025);
DISPLAY INVISIBLE (-175 2025);
FORCEPROP 1 LAST HDL_TAP TRUE
J 2
(-500 1850);
DISPLAY 0.872340 (-500 1850);
DISPLAY INVISIBLE (-500 1850);
FORCEPROP 1 LAST PATH I51
J 2
(-173 1975);
DISPLAY 0.872340 (-173 1975);
PAINT GREEN (-173 1975);
DISPLAY INVISIBLE (-173 1975);
FORCEADD TAP..1
R 2
(-175 2075);
FORCEPROP 3 LASTPIN (-125 2075) SIG_NAME M_B_CPU0_SA_CB<1>
J 0
(-115 2085);
DISPLAY 0.659574 (-115 2085);
PAINT MONO (-115 2085);
DISPLAY INVISIBLE (-115 2085);
FORCEPROP 1 LASTPIN (-125 2075) BN 1
J 2
(-113 2083);
DISPLAY 0.680851 (-113 2083);
PAINT GREEN (-113 2083);
FORCEPROP 2 LAST CDS_LIB standard
J 0
(-175 2075);
DISPLAY INVISIBLE (-175 2075);
FORCEPROP 1 LAST BODY_TYPE PLUMBING
J 2
(-175 2125);
DISPLAY 0.872340 (-175 2125);
PAINT GREEN (-175 2125);
DISPLAY INVISIBLE (-175 2125);
FORCEPROP 1 LAST HDL_TAP TRUE
J 2
(-500 1950);
DISPLAY 0.872340 (-500 1950);
DISPLAY INVISIBLE (-500 1950);
FORCEPROP 1 LAST PATH I52
J 2
(-173 2075);
DISPLAY 0.872340 (-173 2075);
PAINT GREEN (-173 2075);
DISPLAY INVISIBLE (-173 2075);
FORCEADD TAP..1
R 2
(-175 2125);
FORCEPROP 3 LASTPIN (-125 2125) SIG_NAME M_B_CPU0_SA_CB<2>
J 0
(-115 2135);
DISPLAY 0.659574 (-115 2135);
PAINT MONO (-115 2135);
DISPLAY INVISIBLE (-115 2135);
FORCEPROP 1 LASTPIN (-125 2125) BN 2
J 2
(-113 2133);
DISPLAY 0.680851 (-113 2133);
PAINT GREEN (-113 2133);
FORCEPROP 2 LAST CDS_LIB standard
J 0
(-175 2125);
DISPLAY INVISIBLE (-175 2125);
FORCEPROP 1 LAST BODY_TYPE PLUMBING
J 2
(-175 2175);
DISPLAY 0.872340 (-175 2175);
PAINT GREEN (-175 2175);
DISPLAY INVISIBLE (-175 2175);
FORCEPROP 1 LAST HDL_TAP TRUE
J 2
(-500 2000);
DISPLAY 0.872340 (-500 2000);
DISPLAY INVISIBLE (-500 2000);
FORCEPROP 1 LAST PATH I53
J 2
(-173 2125);
DISPLAY 0.872340 (-173 2125);
PAINT GREEN (-173 2125);
DISPLAY INVISIBLE (-173 2125);
FORCEADD TAP..1
R 2
(-175 2175);
FORCEPROP 3 LASTPIN (-125 2175) SIG_NAME M_B_CPU0_SA_CB<3>
J 0
(-115 2185);
DISPLAY 0.659574 (-115 2185);
PAINT MONO (-115 2185);
DISPLAY INVISIBLE (-115 2185);
FORCEPROP 1 LASTPIN (-125 2175) BN 3
J 2
(-113 2183);
DISPLAY 0.680851 (-113 2183);
PAINT GREEN (-113 2183);
FORCEPROP 2 LAST CDS_LIB standard
J 0
(-175 2175);
DISPLAY INVISIBLE (-175 2175);
FORCEPROP 1 LAST BODY_TYPE PLUMBING
J 2
(-175 2225);
DISPLAY 0.872340 (-175 2225);
PAINT GREEN (-175 2225);
DISPLAY INVISIBLE (-175 2225);
FORCEPROP 1 LAST HDL_TAP TRUE
J 2
(-500 2050);
DISPLAY 0.872340 (-500 2050);
DISPLAY INVISIBLE (-500 2050);
FORCEPROP 1 LAST PATH I54
J 2
(-173 2175);
DISPLAY 0.872340 (-173 2175);
PAINT GREEN (-173 2175);
DISPLAY INVISIBLE (-173 2175);
FORCEADD TAP..1
R 2
(-175 2275);
FORCEPROP 3 LASTPIN (-125 2275) SIG_NAME M_B_CPU0_SA_CB<5>
J 0
(-115 2285);
DISPLAY 0.659574 (-115 2285);
PAINT MONO (-115 2285);
DISPLAY INVISIBLE (-115 2285);
FORCEPROP 1 LASTPIN (-125 2275) BN 5
J 2
(-113 2283);
DISPLAY 0.680851 (-113 2283);
PAINT GREEN (-113 2283);
FORCEPROP 2 LAST CDS_LIB standard
J 0
(-175 2275);
DISPLAY INVISIBLE (-175 2275);
FORCEPROP 1 LAST BODY_TYPE PLUMBING
J 2
(-175 2325);
DISPLAY 0.872340 (-175 2325);
PAINT GREEN (-175 2325);
DISPLAY INVISIBLE (-175 2325);
FORCEPROP 1 LAST HDL_TAP TRUE
J 2
(-500 2150);
DISPLAY 0.872340 (-500 2150);
DISPLAY INVISIBLE (-500 2150);
FORCEPROP 1 LAST PATH I55
J 2
(-173 2275);
DISPLAY 0.872340 (-173 2275);
PAINT GREEN (-173 2275);
DISPLAY INVISIBLE (-173 2275);
FORCEADD TAP..1
R 2
(-175 2225);
FORCEPROP 3 LASTPIN (-125 2225) SIG_NAME M_B_CPU0_SA_CB<4>
J 0
(-115 2235);
DISPLAY 0.659574 (-115 2235);
PAINT MONO (-115 2235);
DISPLAY INVISIBLE (-115 2235);
FORCEPROP 1 LASTPIN (-125 2225) BN 4
J 2
(-113 2233);
DISPLAY 0.680851 (-113 2233);
PAINT GREEN (-113 2233);
FORCEPROP 2 LAST CDS_LIB standard
J 0
(-175 2225);
DISPLAY INVISIBLE (-175 2225);
FORCEPROP 1 LAST BODY_TYPE PLUMBING
J 2
(-175 2275);
DISPLAY 0.872340 (-175 2275);
PAINT GREEN (-175 2275);
DISPLAY INVISIBLE (-175 2275);
FORCEPROP 1 LAST HDL_TAP TRUE
J 2
(-500 2100);
DISPLAY 0.872340 (-500 2100);
DISPLAY INVISIBLE (-500 2100);
FORCEPROP 1 LAST PATH I56
J 2
(-173 2225);
DISPLAY 0.872340 (-173 2225);
PAINT GREEN (-173 2225);
DISPLAY INVISIBLE (-173 2225);
FORCEADD TAP..1
R 2
(-175 2325);
FORCEPROP 3 LASTPIN (-125 2325) SIG_NAME M_B_CPU0_SA_CB<6>
J 0
(-115 2335);
DISPLAY 0.659574 (-115 2335);
PAINT MONO (-115 2335);
DISPLAY INVISIBLE (-115 2335);
FORCEPROP 1 LASTPIN (-125 2325) BN 6
J 2
(-113 2333);
DISPLAY 0.680851 (-113 2333);
PAINT GREEN (-113 2333);
FORCEPROP 2 LAST CDS_LIB standard
J 0
(-175 2325);
DISPLAY INVISIBLE (-175 2325);
FORCEPROP 1 LAST BODY_TYPE PLUMBING
J 2
(-175 2375);
DISPLAY 0.872340 (-175 2375);
PAINT GREEN (-175 2375);
DISPLAY INVISIBLE (-175 2375);
FORCEPROP 1 LAST HDL_TAP TRUE
J 2
(-500 2200);
DISPLAY 0.872340 (-500 2200);
DISPLAY INVISIBLE (-500 2200);
FORCEPROP 1 LAST PATH I57
J 2
(-173 2325);
DISPLAY 0.872340 (-173 2325);
PAINT GREEN (-173 2325);
DISPLAY INVISIBLE (-173 2325);
FORCEADD TAP..1
R 2
(-175 2525);
FORCEPROP 3 LASTPIN (-125 2525) SIG_NAME M_B_CPU0_SA_DQ<2>
J 0
(-115 2535);
DISPLAY 0.659574 (-115 2535);
PAINT MONO (-115 2535);
DISPLAY INVISIBLE (-115 2535);
FORCEPROP 1 LASTPIN (-125 2525) BN 2
J 2
(-113 2533);
DISPLAY 0.680851 (-113 2533);
PAINT GREEN (-113 2533);
FORCEPROP 2 LAST CDS_LIB standard
J 0
(-175 2525);
DISPLAY INVISIBLE (-175 2525);
FORCEPROP 1 LAST BODY_TYPE PLUMBING
J 2
(-175 2575);
DISPLAY 0.872340 (-175 2575);
PAINT GREEN (-175 2575);
DISPLAY INVISIBLE (-175 2575);
FORCEPROP 1 LAST HDL_TAP TRUE
J 2
(-500 2400);
DISPLAY 0.872340 (-500 2400);
DISPLAY INVISIBLE (-500 2400);
FORCEPROP 1 LAST PATH I58
J 2
(-173 2525);
DISPLAY 0.872340 (-173 2525);
PAINT GREEN (-173 2525);
DISPLAY INVISIBLE (-173 2525);
FORCEADD TAP..1
R 2
(-175 2475);
FORCEPROP 3 LASTPIN (-125 2475) SIG_NAME M_B_CPU0_SA_DQ<1>
J 0
(-115 2485);
DISPLAY 0.659574 (-115 2485);
PAINT MONO (-115 2485);
DISPLAY INVISIBLE (-115 2485);
FORCEPROP 1 LASTPIN (-125 2475) BN 1
J 2
(-113 2483);
DISPLAY 0.680851 (-113 2483);
PAINT GREEN (-113 2483);
FORCEPROP 2 LAST CDS_LIB standard
J 0
(-175 2475);
DISPLAY INVISIBLE (-175 2475);
FORCEPROP 1 LAST BODY_TYPE PLUMBING
J 2
(-175 2525);
DISPLAY 0.872340 (-175 2525);
PAINT GREEN (-175 2525);
DISPLAY INVISIBLE (-175 2525);
FORCEPROP 1 LAST HDL_TAP TRUE
J 2
(-500 2350);
DISPLAY 0.872340 (-500 2350);
DISPLAY INVISIBLE (-500 2350);
FORCEPROP 1 LAST PATH I59
J 2
(-173 2475);
DISPLAY 0.872340 (-173 2475);
PAINT GREEN (-173 2475);
DISPLAY INVISIBLE (-173 2475);
FORCEADD TAP..1
R 2
(-175 -125);
FORCEPROP 3 LASTPIN (-125 -125) SIG_NAME M_B_CPU0_CLK_DP<0>
J 0
(-115 -115);
DISPLAY 0.659574 (-115 -115);
PAINT MONO (-115 -115);
DISPLAY INVISIBLE (-115 -115);
FORCEPROP 1 LASTPIN (-125 -125) BN 0
J 2
(-113 -117);
DISPLAY 0.680851 (-113 -117);
PAINT GREEN (-113 -117);
FORCEPROP 2 LAST CDS_LIB standard
J 0
(-175 -125);
DISPLAY INVISIBLE (-175 -125);
FORCEPROP 1 LAST BODY_TYPE PLUMBING
J 2
(-175 -75);
DISPLAY 0.872340 (-175 -75);
PAINT GREEN (-175 -75);
DISPLAY INVISIBLE (-175 -75);
FORCEPROP 1 LAST HDL_TAP TRUE
J 2
(-500 -250);
DISPLAY 0.872340 (-500 -250);
DISPLAY INVISIBLE (-500 -250);
FORCEPROP 1 LAST PATH I6
J 2
(-173 -125);
DISPLAY 0.872340 (-173 -125);
PAINT GREEN (-173 -125);
DISPLAY INVISIBLE (-173 -125);
FORCEADD TAP..1
R 2
(-175 2425);
FORCEPROP 3 LASTPIN (-125 2425) SIG_NAME M_B_CPU0_SA_DQ<0>
J 0
(-115 2435);
DISPLAY 0.659574 (-115 2435);
PAINT MONO (-115 2435);
DISPLAY INVISIBLE (-115 2435);
FORCEPROP 1 LASTPIN (-125 2425) BN 0
J 2
(-113 2433);
DISPLAY 0.680851 (-113 2433);
PAINT GREEN (-113 2433);
FORCEPROP 2 LAST CDS_LIB standard
J 0
(-175 2425);
DISPLAY INVISIBLE (-175 2425);
FORCEPROP 1 LAST BODY_TYPE PLUMBING
J 2
(-175 2475);
DISPLAY 0.872340 (-175 2475);
PAINT GREEN (-175 2475);
DISPLAY INVISIBLE (-175 2475);
FORCEPROP 1 LAST HDL_TAP TRUE
J 2
(-500 2300);
DISPLAY 0.872340 (-500 2300);
DISPLAY INVISIBLE (-500 2300);
FORCEPROP 1 LAST PATH I60
J 2
(-173 2425);
DISPLAY 0.872340 (-173 2425);
PAINT GREEN (-173 2425);
DISPLAY INVISIBLE (-173 2425);
FORCEADD TAP..1
R 2
(-175 2375);
FORCEPROP 3 LASTPIN (-125 2375) SIG_NAME M_B_CPU0_SA_CB<7>
J 0
(-115 2385);
DISPLAY 0.659574 (-115 2385);
PAINT MONO (-115 2385);
DISPLAY INVISIBLE (-115 2385);
FORCEPROP 1 LASTPIN (-125 2375) BN 7
J 2
(-113 2383);
DISPLAY 0.680851 (-113 2383);
PAINT GREEN (-113 2383);
FORCEPROP 2 LAST CDS_LIB standard
J 0
(-175 2375);
DISPLAY INVISIBLE (-175 2375);
FORCEPROP 1 LAST BODY_TYPE PLUMBING
J 2
(-175 2425);
DISPLAY 0.872340 (-175 2425);
PAINT GREEN (-175 2425);
DISPLAY INVISIBLE (-175 2425);
FORCEPROP 1 LAST HDL_TAP TRUE
J 2
(-500 2250);
DISPLAY 0.872340 (-500 2250);
DISPLAY INVISIBLE (-500 2250);
FORCEPROP 1 LAST PATH I61
J 2
(-173 2375);
DISPLAY 0.872340 (-173 2375);
PAINT GREEN (-173 2375);
DISPLAY INVISIBLE (-173 2375);
FORCEADD TAP..1
R 2
(-175 2575);
FORCEPROP 3 LASTPIN (-125 2575) SIG_NAME M_B_CPU0_SA_DQ<3>
J 0
(-115 2585);
DISPLAY 0.659574 (-115 2585);
PAINT MONO (-115 2585);
DISPLAY INVISIBLE (-115 2585);
FORCEPROP 1 LASTPIN (-125 2575) BN 3
J 2
(-113 2583);
DISPLAY 0.680851 (-113 2583);
PAINT GREEN (-113 2583);
FORCEPROP 2 LAST CDS_LIB standard
J 0
(-175 2575);
DISPLAY INVISIBLE (-175 2575);
FORCEPROP 1 LAST BODY_TYPE PLUMBING
J 2
(-175 2625);
DISPLAY 0.872340 (-175 2625);
PAINT GREEN (-175 2625);
DISPLAY INVISIBLE (-175 2625);
FORCEPROP 1 LAST HDL_TAP TRUE
J 2
(-500 2450);
DISPLAY 0.872340 (-500 2450);
DISPLAY INVISIBLE (-500 2450);
FORCEPROP 1 LAST PATH I62
J 2
(-173 2575);
DISPLAY 0.872340 (-173 2575);
PAINT GREEN (-173 2575);
DISPLAY INVISIBLE (-173 2575);
FORCEADD TAP..1
R 2
(-175 2625);
FORCEPROP 3 LASTPIN (-125 2625) SIG_NAME M_B_CPU0_SA_DQ<4>
J 0
(-115 2635);
DISPLAY 0.659574 (-115 2635);
PAINT MONO (-115 2635);
DISPLAY INVISIBLE (-115 2635);
FORCEPROP 1 LASTPIN (-125 2625) BN 4
J 2
(-113 2633);
DISPLAY 0.680851 (-113 2633);
PAINT GREEN (-113 2633);
FORCEPROP 2 LAST CDS_LIB standard
J 0
(-175 2625);
DISPLAY INVISIBLE (-175 2625);
FORCEPROP 1 LAST BODY_TYPE PLUMBING
J 2
(-175 2675);
DISPLAY 0.872340 (-175 2675);
PAINT GREEN (-175 2675);
DISPLAY INVISIBLE (-175 2675);
FORCEPROP 1 LAST HDL_TAP TRUE
J 2
(-500 2500);
DISPLAY 0.872340 (-500 2500);
DISPLAY INVISIBLE (-500 2500);
FORCEPROP 1 LAST PATH I63
J 2
(-173 2625);
DISPLAY 0.872340 (-173 2625);
PAINT GREEN (-173 2625);
DISPLAY INVISIBLE (-173 2625);
FORCEADD TAP..1
R 2
(-175 2675);
FORCEPROP 3 LASTPIN (-125 2675) SIG_NAME M_B_CPU0_SA_DQ<5>
J 0
(-115 2685);
DISPLAY 0.659574 (-115 2685);
PAINT MONO (-115 2685);
DISPLAY INVISIBLE (-115 2685);
FORCEPROP 1 LASTPIN (-125 2675) BN 5
J 2
(-113 2683);
DISPLAY 0.680851 (-113 2683);
PAINT GREEN (-113 2683);
FORCEPROP 2 LAST CDS_LIB standard
J 0
(-175 2675);
DISPLAY INVISIBLE (-175 2675);
FORCEPROP 1 LAST BODY_TYPE PLUMBING
J 2
(-175 2725);
DISPLAY 0.872340 (-175 2725);
PAINT GREEN (-175 2725);
DISPLAY INVISIBLE (-175 2725);
FORCEPROP 1 LAST HDL_TAP TRUE
J 2
(-500 2550);
DISPLAY 0.872340 (-500 2550);
DISPLAY INVISIBLE (-500 2550);
FORCEPROP 1 LAST PATH I64
J 2
(-173 2675);
DISPLAY 0.872340 (-173 2675);
PAINT GREEN (-173 2675);
DISPLAY INVISIBLE (-173 2675);
FORCEADD TAP..1
R 2
(-175 2775);
FORCEPROP 3 LASTPIN (-125 2775) SIG_NAME M_B_CPU0_SA_DQ<7>
J 0
(-115 2785);
DISPLAY 0.659574 (-115 2785);
PAINT MONO (-115 2785);
DISPLAY INVISIBLE (-115 2785);
FORCEPROP 1 LASTPIN (-125 2775) BN 7
J 2
(-113 2783);
DISPLAY 0.680851 (-113 2783);
PAINT GREEN (-113 2783);
FORCEPROP 2 LAST CDS_LIB standard
J 0
(-175 2775);
DISPLAY INVISIBLE (-175 2775);
FORCEPROP 1 LAST BODY_TYPE PLUMBING
J 2
(-175 2825);
DISPLAY 0.872340 (-175 2825);
PAINT GREEN (-175 2825);
DISPLAY INVISIBLE (-175 2825);
FORCEPROP 1 LAST HDL_TAP TRUE
J 2
(-500 2650);
DISPLAY 0.872340 (-500 2650);
DISPLAY INVISIBLE (-500 2650);
FORCEPROP 1 LAST PATH I65
J 2
(-173 2775);
DISPLAY 0.872340 (-173 2775);
PAINT GREEN (-173 2775);
DISPLAY INVISIBLE (-173 2775);
FORCEADD TAP..1
R 2
(-175 2725);
FORCEPROP 3 LASTPIN (-125 2725) SIG_NAME M_B_CPU0_SA_DQ<6>
J 0
(-115 2735);
DISPLAY 0.659574 (-115 2735);
PAINT MONO (-115 2735);
DISPLAY INVISIBLE (-115 2735);
FORCEPROP 1 LASTPIN (-125 2725) BN 6
J 2
(-113 2733);
DISPLAY 0.680851 (-113 2733);
PAINT GREEN (-113 2733);
FORCEPROP 2 LAST CDS_LIB standard
J 0
(-175 2725);
DISPLAY INVISIBLE (-175 2725);
FORCEPROP 1 LAST BODY_TYPE PLUMBING
J 2
(-175 2775);
DISPLAY 0.872340 (-175 2775);
PAINT GREEN (-175 2775);
DISPLAY INVISIBLE (-175 2775);
FORCEPROP 1 LAST HDL_TAP TRUE
J 2
(-500 2600);
DISPLAY 0.872340 (-500 2600);
DISPLAY INVISIBLE (-500 2600);
FORCEPROP 1 LAST PATH I66
J 2
(-173 2725);
DISPLAY 0.872340 (-173 2725);
PAINT GREEN (-173 2725);
DISPLAY INVISIBLE (-173 2725);
FORCEADD TAP..1
R 2
(-175 2825);
FORCEPROP 3 LASTPIN (-125 2825) SIG_NAME M_B_CPU0_SA_DQ<8>
J 0
(-115 2835);
DISPLAY 0.659574 (-115 2835);
PAINT MONO (-115 2835);
DISPLAY INVISIBLE (-115 2835);
FORCEPROP 1 LASTPIN (-125 2825) BN 8
J 2
(-113 2833);
DISPLAY 0.680851 (-113 2833);
PAINT GREEN (-113 2833);
FORCEPROP 2 LAST CDS_LIB standard
J 0
(-175 2825);
DISPLAY INVISIBLE (-175 2825);
FORCEPROP 1 LAST BODY_TYPE PLUMBING
J 2
(-175 2875);
DISPLAY 0.872340 (-175 2875);
PAINT GREEN (-175 2875);
DISPLAY INVISIBLE (-175 2875);
FORCEPROP 1 LAST HDL_TAP TRUE
J 2
(-500 2700);
DISPLAY 0.872340 (-500 2700);
DISPLAY INVISIBLE (-500 2700);
FORCEPROP 1 LAST PATH I67
J 2
(-173 2825);
DISPLAY 0.872340 (-173 2825);
PAINT GREEN (-173 2825);
DISPLAY INVISIBLE (-173 2825);
FORCEADD TAP..1
R 2
(-175 2925);
FORCEPROP 3 LASTPIN (-125 2925) SIG_NAME M_B_CPU0_SA_DQ<10>
J 0
(-115 2935);
DISPLAY 0.659574 (-115 2935);
PAINT MONO (-115 2935);
DISPLAY INVISIBLE (-115 2935);
FORCEPROP 1 LASTPIN (-125 2925) BN 10
J 2
(-113 2933);
DISPLAY 0.680851 (-113 2933);
PAINT GREEN (-113 2933);
FORCEPROP 2 LAST CDS_LIB standard
J 0
(-175 2925);
DISPLAY INVISIBLE (-175 2925);
FORCEPROP 1 LAST BODY_TYPE PLUMBING
J 2
(-175 2975);
DISPLAY 0.872340 (-175 2975);
PAINT GREEN (-175 2975);
DISPLAY INVISIBLE (-175 2975);
FORCEPROP 1 LAST HDL_TAP TRUE
J 2
(-500 2800);
DISPLAY 0.872340 (-500 2800);
DISPLAY INVISIBLE (-500 2800);
FORCEPROP 1 LAST PATH I68
J 2
(-173 2925);
DISPLAY 0.872340 (-173 2925);
PAINT GREEN (-173 2925);
DISPLAY INVISIBLE (-173 2925);
FORCEADD TAP..1
R 2
(-175 2875);
FORCEPROP 3 LASTPIN (-125 2875) SIG_NAME M_B_CPU0_SA_DQ<9>
J 0
(-115 2885);
DISPLAY 0.659574 (-115 2885);
PAINT MONO (-115 2885);
DISPLAY INVISIBLE (-115 2885);
FORCEPROP 1 LASTPIN (-125 2875) BN 9
J 2
(-113 2883);
DISPLAY 0.680851 (-113 2883);
PAINT GREEN (-113 2883);
FORCEPROP 2 LAST CDS_LIB standard
J 0
(-175 2875);
DISPLAY INVISIBLE (-175 2875);
FORCEPROP 1 LAST BODY_TYPE PLUMBING
J 2
(-175 2925);
DISPLAY 0.872340 (-175 2925);
PAINT GREEN (-175 2925);
DISPLAY INVISIBLE (-175 2925);
FORCEPROP 1 LAST HDL_TAP TRUE
J 2
(-500 2750);
DISPLAY 0.872340 (-500 2750);
DISPLAY INVISIBLE (-500 2750);
FORCEPROP 1 LAST PATH I69
J 2
(-173 2875);
DISPLAY 0.872340 (-173 2875);
PAINT GREEN (-173 2875);
DISPLAY INVISIBLE (-173 2875);
FORCEADD TAP..1
R 2
(-175 -75);
FORCEPROP 3 LASTPIN (-125 -75) SIG_NAME M_B_CPU0_CLK_DP<1>
J 0
(-115 -65);
DISPLAY 0.659574 (-115 -65);
PAINT MONO (-115 -65);
DISPLAY INVISIBLE (-115 -65);
FORCEPROP 1 LASTPIN (-125 -75) BN 1
J 2
(-113 -67);
DISPLAY 0.680851 (-113 -67);
PAINT GREEN (-113 -67);
FORCEPROP 2 LAST CDS_LIB standard
J 0
(-175 -75);
DISPLAY INVISIBLE (-175 -75);
FORCEPROP 1 LAST BODY_TYPE PLUMBING
J 2
(-175 -25);
DISPLAY 0.872340 (-175 -25);
PAINT GREEN (-175 -25);
DISPLAY INVISIBLE (-175 -25);
FORCEPROP 1 LAST HDL_TAP TRUE
J 2
(-500 -200);
DISPLAY 0.872340 (-500 -200);
DISPLAY INVISIBLE (-500 -200);
FORCEPROP 1 LAST PATH I7
J 2
(-173 -75);
DISPLAY 0.872340 (-173 -75);
PAINT GREEN (-173 -75);
DISPLAY INVISIBLE (-173 -75);
FORCEADD TAP..1
R 2
(-175 3075);
FORCEPROP 3 LASTPIN (-125 3075) SIG_NAME M_B_CPU0_SA_DQ<13>
J 0
(-115 3085);
DISPLAY 0.659574 (-115 3085);
PAINT MONO (-115 3085);
DISPLAY INVISIBLE (-115 3085);
FORCEPROP 1 LASTPIN (-125 3075) BN 13
J 2
(-113 3083);
DISPLAY 0.680851 (-113 3083);
PAINT GREEN (-113 3083);
FORCEPROP 2 LAST CDS_LIB standard
J 0
(-175 3075);
DISPLAY INVISIBLE (-175 3075);
FORCEPROP 1 LAST BODY_TYPE PLUMBING
J 2
(-175 3125);
DISPLAY 0.872340 (-175 3125);
PAINT GREEN (-175 3125);
DISPLAY INVISIBLE (-175 3125);
FORCEPROP 1 LAST HDL_TAP TRUE
J 2
(-500 2950);
DISPLAY 0.872340 (-500 2950);
DISPLAY INVISIBLE (-500 2950);
FORCEPROP 1 LAST PATH I70
J 2
(-173 3075);
DISPLAY 0.872340 (-173 3075);
PAINT GREEN (-173 3075);
DISPLAY INVISIBLE (-173 3075);
FORCEADD TAP..1
R 2
(-175 2975);
FORCEPROP 3 LASTPIN (-125 2975) SIG_NAME M_B_CPU0_SA_DQ<11>
J 0
(-115 2985);
DISPLAY 0.659574 (-115 2985);
PAINT MONO (-115 2985);
DISPLAY INVISIBLE (-115 2985);
FORCEPROP 1 LASTPIN (-125 2975) BN 11
J 2
(-113 2983);
DISPLAY 0.680851 (-113 2983);
PAINT GREEN (-113 2983);
FORCEPROP 2 LAST CDS_LIB standard
J 0
(-175 2975);
DISPLAY INVISIBLE (-175 2975);
FORCEPROP 1 LAST BODY_TYPE PLUMBING
J 2
(-175 3025);
DISPLAY 0.872340 (-175 3025);
PAINT GREEN (-175 3025);
DISPLAY INVISIBLE (-175 3025);
FORCEPROP 1 LAST HDL_TAP TRUE
J 2
(-500 2850);
DISPLAY 0.872340 (-500 2850);
DISPLAY INVISIBLE (-500 2850);
FORCEPROP 1 LAST PATH I71
J 2
(-173 2975);
DISPLAY 0.872340 (-173 2975);
PAINT GREEN (-173 2975);
DISPLAY INVISIBLE (-173 2975);
FORCEADD TAP..1
R 2
(-175 3025);
FORCEPROP 3 LASTPIN (-125 3025) SIG_NAME M_B_CPU0_SA_DQ<12>
J 0
(-115 3035);
DISPLAY 0.659574 (-115 3035);
PAINT MONO (-115 3035);
DISPLAY INVISIBLE (-115 3035);
FORCEPROP 1 LASTPIN (-125 3025) BN 12
J 2
(-113 3033);
DISPLAY 0.680851 (-113 3033);
PAINT GREEN (-113 3033);
FORCEPROP 2 LAST CDS_LIB standard
J 0
(-175 3025);
DISPLAY INVISIBLE (-175 3025);
FORCEPROP 1 LAST BODY_TYPE PLUMBING
J 2
(-175 3075);
DISPLAY 0.872340 (-175 3075);
PAINT GREEN (-175 3075);
DISPLAY INVISIBLE (-175 3075);
FORCEPROP 1 LAST HDL_TAP TRUE
J 2
(-500 2900);
DISPLAY 0.872340 (-500 2900);
DISPLAY INVISIBLE (-500 2900);
FORCEPROP 1 LAST PATH I72
J 2
(-173 3025);
DISPLAY 0.872340 (-173 3025);
PAINT GREEN (-173 3025);
DISPLAY INVISIBLE (-173 3025);
FORCEADD TAP..1
R 2
(-175 3125);
FORCEPROP 3 LASTPIN (-125 3125) SIG_NAME M_B_CPU0_SA_DQ<14>
J 0
(-115 3135);
DISPLAY 0.659574 (-115 3135);
PAINT MONO (-115 3135);
DISPLAY INVISIBLE (-115 3135);
FORCEPROP 1 LASTPIN (-125 3125) BN 14
J 2
(-113 3133);
DISPLAY 0.680851 (-113 3133);
PAINT GREEN (-113 3133);
FORCEPROP 2 LAST CDS_LIB standard
J 0
(-175 3125);
DISPLAY INVISIBLE (-175 3125);
FORCEPROP 1 LAST BODY_TYPE PLUMBING
J 2
(-175 3175);
DISPLAY 0.872340 (-175 3175);
PAINT GREEN (-175 3175);
DISPLAY INVISIBLE (-175 3175);
FORCEPROP 1 LAST HDL_TAP TRUE
J 2
(-500 3000);
DISPLAY 0.872340 (-500 3000);
DISPLAY INVISIBLE (-500 3000);
FORCEPROP 1 LAST PATH I73
J 2
(-173 3125);
DISPLAY 0.872340 (-173 3125);
PAINT GREEN (-173 3125);
DISPLAY INVISIBLE (-173 3125);
FORCEADD TAP..1
R 2
(-175 3175);
FORCEPROP 3 LASTPIN (-125 3175) SIG_NAME M_B_CPU0_SA_DQ<15>
J 0
(-115 3185);
DISPLAY 0.659574 (-115 3185);
PAINT MONO (-115 3185);
DISPLAY INVISIBLE (-115 3185);
FORCEPROP 1 LASTPIN (-125 3175) BN 15
J 2
(-113 3183);
DISPLAY 0.680851 (-113 3183);
PAINT GREEN (-113 3183);
FORCEPROP 2 LAST CDS_LIB standard
J 0
(-175 3175);
DISPLAY INVISIBLE (-175 3175);
FORCEPROP 1 LAST BODY_TYPE PLUMBING
J 2
(-175 3225);
DISPLAY 0.872340 (-175 3225);
PAINT GREEN (-175 3225);
DISPLAY INVISIBLE (-175 3225);
FORCEPROP 1 LAST HDL_TAP TRUE
J 2
(-500 3050);
DISPLAY 0.872340 (-500 3050);
DISPLAY INVISIBLE (-500 3050);
FORCEPROP 1 LAST PATH I74
J 2
(-173 3175);
DISPLAY 0.872340 (-173 3175);
PAINT GREEN (-173 3175);
DISPLAY INVISIBLE (-173 3175);
FORCEADD TAP..1
R 2
(-175 3325);
FORCEPROP 3 LASTPIN (-125 3325) SIG_NAME M_B_CPU0_SA_DQ<18>
J 0
(-115 3335);
DISPLAY 0.659574 (-115 3335);
PAINT MONO (-115 3335);
DISPLAY INVISIBLE (-115 3335);
FORCEPROP 1 LASTPIN (-125 3325) BN 18
J 2
(-113 3333);
DISPLAY 0.680851 (-113 3333);
PAINT GREEN (-113 3333);
FORCEPROP 2 LAST CDS_LIB standard
J 0
(-175 3325);
DISPLAY INVISIBLE (-175 3325);
FORCEPROP 1 LAST BODY_TYPE PLUMBING
J 2
(-175 3375);
DISPLAY 0.872340 (-175 3375);
PAINT GREEN (-175 3375);
DISPLAY INVISIBLE (-175 3375);
FORCEPROP 1 LAST HDL_TAP TRUE
J 2
(-500 3200);
DISPLAY 0.872340 (-500 3200);
DISPLAY INVISIBLE (-500 3200);
FORCEPROP 1 LAST PATH I75
J 2
(-173 3325);
DISPLAY 0.872340 (-173 3325);
PAINT GREEN (-173 3325);
DISPLAY INVISIBLE (-173 3325);
FORCEADD TAP..1
R 2
(-175 3275);
FORCEPROP 3 LASTPIN (-125 3275) SIG_NAME M_B_CPU0_SA_DQ<17>
J 0
(-115 3285);
DISPLAY 0.659574 (-115 3285);
PAINT MONO (-115 3285);
DISPLAY INVISIBLE (-115 3285);
FORCEPROP 1 LASTPIN (-125 3275) BN 17
J 2
(-113 3283);
DISPLAY 0.680851 (-113 3283);
PAINT GREEN (-113 3283);
FORCEPROP 2 LAST CDS_LIB standard
J 0
(-175 3275);
DISPLAY INVISIBLE (-175 3275);
FORCEPROP 1 LAST BODY_TYPE PLUMBING
J 2
(-175 3325);
DISPLAY 0.872340 (-175 3325);
PAINT GREEN (-175 3325);
DISPLAY INVISIBLE (-175 3325);
FORCEPROP 1 LAST HDL_TAP TRUE
J 2
(-500 3150);
DISPLAY 0.872340 (-500 3150);
DISPLAY INVISIBLE (-500 3150);
FORCEPROP 1 LAST PATH I76
J 2
(-173 3275);
DISPLAY 0.872340 (-173 3275);
PAINT GREEN (-173 3275);
DISPLAY INVISIBLE (-173 3275);
FORCEADD TAP..1
R 2
(-175 3225);
FORCEPROP 3 LASTPIN (-125 3225) SIG_NAME M_B_CPU0_SA_DQ<16>
J 0
(-115 3235);
DISPLAY 0.659574 (-115 3235);
PAINT MONO (-115 3235);
DISPLAY INVISIBLE (-115 3235);
FORCEPROP 1 LASTPIN (-125 3225) BN 16
J 2
(-113 3233);
DISPLAY 0.680851 (-113 3233);
PAINT GREEN (-113 3233);
FORCEPROP 2 LAST CDS_LIB standard
J 0
(-175 3225);
DISPLAY INVISIBLE (-175 3225);
FORCEPROP 1 LAST BODY_TYPE PLUMBING
J 2
(-175 3275);
DISPLAY 0.872340 (-175 3275);
PAINT GREEN (-175 3275);
DISPLAY INVISIBLE (-175 3275);
FORCEPROP 1 LAST HDL_TAP TRUE
J 2
(-500 3100);
DISPLAY 0.872340 (-500 3100);
DISPLAY INVISIBLE (-500 3100);
FORCEPROP 1 LAST PATH I77
J 2
(-173 3225);
DISPLAY 0.872340 (-173 3225);
PAINT GREEN (-173 3225);
DISPLAY INVISIBLE (-173 3225);
FORCEADD TAP..1
R 2
(-175 3375);
FORCEPROP 3 LASTPIN (-125 3375) SIG_NAME M_B_CPU0_SA_DQ<19>
J 0
(-115 3385);
DISPLAY 0.659574 (-115 3385);
PAINT MONO (-115 3385);
DISPLAY INVISIBLE (-115 3385);
FORCEPROP 1 LASTPIN (-125 3375) BN 19
J 2
(-113 3383);
DISPLAY 0.680851 (-113 3383);
PAINT GREEN (-113 3383);
FORCEPROP 2 LAST CDS_LIB standard
J 0
(-175 3375);
DISPLAY INVISIBLE (-175 3375);
FORCEPROP 1 LAST BODY_TYPE PLUMBING
J 2
(-175 3425);
DISPLAY 0.872340 (-175 3425);
PAINT GREEN (-175 3425);
DISPLAY INVISIBLE (-175 3425);
FORCEPROP 1 LAST HDL_TAP TRUE
J 2
(-500 3250);
DISPLAY 0.872340 (-500 3250);
DISPLAY INVISIBLE (-500 3250);
FORCEPROP 1 LAST PATH I78
J 2
(-173 3375);
DISPLAY 0.872340 (-173 3375);
PAINT GREEN (-173 3375);
DISPLAY INVISIBLE (-173 3375);
FORCEADD TAP..1
R 2
(-175 3425);
FORCEPROP 3 LASTPIN (-125 3425) SIG_NAME M_B_CPU0_SA_DQ<20>
J 0
(-115 3435);
DISPLAY 0.659574 (-115 3435);
PAINT MONO (-115 3435);
DISPLAY INVISIBLE (-115 3435);
FORCEPROP 1 LASTPIN (-125 3425) BN 20
J 2
(-113 3433);
DISPLAY 0.680851 (-113 3433);
PAINT GREEN (-113 3433);
FORCEPROP 2 LAST CDS_LIB standard
J 0
(-175 3425);
DISPLAY INVISIBLE (-175 3425);
FORCEPROP 1 LAST BODY_TYPE PLUMBING
J 2
(-175 3475);
DISPLAY 0.872340 (-175 3475);
PAINT GREEN (-175 3475);
DISPLAY INVISIBLE (-175 3475);
FORCEPROP 1 LAST HDL_TAP TRUE
J 2
(-500 3300);
DISPLAY 0.872340 (-500 3300);
DISPLAY INVISIBLE (-500 3300);
FORCEPROP 1 LAST PATH I79
J 2
(-173 3425);
DISPLAY 0.872340 (-173 3425);
PAINT GREEN (-173 3425);
DISPLAY INVISIBLE (-173 3425);
FORCEADD TAP..1
R 2
(-175 -175);
FORCEPROP 3 LASTPIN (-125 -175) SIG_NAME M_B_CPU0_CLK_DN<1>
J 0
(-115 -165);
DISPLAY 0.659574 (-115 -165);
PAINT MONO (-115 -165);
DISPLAY INVISIBLE (-115 -165);
FORCEPROP 1 LASTPIN (-125 -175) BN 1
J 2
(-113 -167);
DISPLAY 0.680851 (-113 -167);
PAINT GREEN (-113 -167);
FORCEPROP 2 LAST CDS_LIB standard
J 0
(-175 -175);
DISPLAY INVISIBLE (-175 -175);
FORCEPROP 1 LAST BODY_TYPE PLUMBING
J 2
(-175 -125);
DISPLAY 0.872340 (-175 -125);
PAINT GREEN (-175 -125);
DISPLAY INVISIBLE (-175 -125);
FORCEPROP 1 LAST HDL_TAP TRUE
J 2
(-500 -300);
DISPLAY 0.872340 (-500 -300);
DISPLAY INVISIBLE (-500 -300);
FORCEPROP 1 LAST PATH I8
J 2
(-173 -175);
DISPLAY 0.872340 (-173 -175);
PAINT GREEN (-173 -175);
DISPLAY INVISIBLE (-173 -175);
FORCEADD TAP..1
R 2
(-175 3575);
FORCEPROP 3 LASTPIN (-125 3575) SIG_NAME M_B_CPU0_SA_DQ<23>
J 0
(-115 3585);
DISPLAY 0.659574 (-115 3585);
PAINT MONO (-115 3585);
DISPLAY INVISIBLE (-115 3585);
FORCEPROP 1 LASTPIN (-125 3575) BN 23
J 2
(-113 3583);
DISPLAY 0.680851 (-113 3583);
PAINT GREEN (-113 3583);
FORCEPROP 2 LAST CDS_LIB standard
J 0
(-175 3575);
DISPLAY INVISIBLE (-175 3575);
FORCEPROP 1 LAST BODY_TYPE PLUMBING
J 2
(-175 3625);
DISPLAY 0.872340 (-175 3625);
PAINT GREEN (-175 3625);
DISPLAY INVISIBLE (-175 3625);
FORCEPROP 1 LAST HDL_TAP TRUE
J 2
(-500 3450);
DISPLAY 0.872340 (-500 3450);
DISPLAY INVISIBLE (-500 3450);
FORCEPROP 1 LAST PATH I80
J 2
(-173 3575);
DISPLAY 0.872340 (-173 3575);
PAINT GREEN (-173 3575);
DISPLAY INVISIBLE (-173 3575);
FORCEADD TAP..1
R 2
(-175 3525);
FORCEPROP 3 LASTPIN (-125 3525) SIG_NAME M_B_CPU0_SA_DQ<22>
J 0
(-115 3535);
DISPLAY 0.659574 (-115 3535);
PAINT MONO (-115 3535);
DISPLAY INVISIBLE (-115 3535);
FORCEPROP 1 LASTPIN (-125 3525) BN 22
J 2
(-113 3533);
DISPLAY 0.680851 (-113 3533);
PAINT GREEN (-113 3533);
FORCEPROP 2 LAST CDS_LIB standard
J 0
(-175 3525);
DISPLAY INVISIBLE (-175 3525);
FORCEPROP 1 LAST BODY_TYPE PLUMBING
J 2
(-175 3575);
DISPLAY 0.872340 (-175 3575);
PAINT GREEN (-175 3575);
DISPLAY INVISIBLE (-175 3575);
FORCEPROP 1 LAST HDL_TAP TRUE
J 2
(-500 3400);
DISPLAY 0.872340 (-500 3400);
DISPLAY INVISIBLE (-500 3400);
FORCEPROP 1 LAST PATH I81
J 2
(-173 3525);
DISPLAY 0.872340 (-173 3525);
PAINT GREEN (-173 3525);
DISPLAY INVISIBLE (-173 3525);
FORCEADD TAP..1
R 2
(-175 3475);
FORCEPROP 3 LASTPIN (-125 3475) SIG_NAME M_B_CPU0_SA_DQ<21>
J 0
(-115 3485);
DISPLAY 0.659574 (-115 3485);
PAINT MONO (-115 3485);
DISPLAY INVISIBLE (-115 3485);
FORCEPROP 1 LASTPIN (-125 3475) BN 21
J 2
(-113 3483);
DISPLAY 0.680851 (-113 3483);
PAINT GREEN (-113 3483);
FORCEPROP 2 LAST CDS_LIB standard
J 0
(-175 3475);
DISPLAY INVISIBLE (-175 3475);
FORCEPROP 1 LAST BODY_TYPE PLUMBING
J 2
(-175 3525);
DISPLAY 0.872340 (-175 3525);
PAINT GREEN (-175 3525);
DISPLAY INVISIBLE (-175 3525);
FORCEPROP 1 LAST HDL_TAP TRUE
J 2
(-500 3350);
DISPLAY 0.872340 (-500 3350);
DISPLAY INVISIBLE (-500 3350);
FORCEPROP 1 LAST PATH I82
J 2
(-173 3475);
DISPLAY 0.872340 (-173 3475);
PAINT GREEN (-173 3475);
DISPLAY INVISIBLE (-173 3475);
FORCEADD TAP..1
R 2
(-175 3625);
FORCEPROP 3 LASTPIN (-125 3625) SIG_NAME M_B_CPU0_SA_DQ<24>
J 0
(-115 3635);
DISPLAY 0.659574 (-115 3635);
PAINT MONO (-115 3635);
DISPLAY INVISIBLE (-115 3635);
FORCEPROP 1 LASTPIN (-125 3625) BN 24
J 2
(-113 3633);
DISPLAY 0.680851 (-113 3633);
PAINT GREEN (-113 3633);
FORCEPROP 2 LAST CDS_LIB standard
J 0
(-175 3625);
DISPLAY INVISIBLE (-175 3625);
FORCEPROP 1 LAST BODY_TYPE PLUMBING
J 2
(-175 3675);
DISPLAY 0.872340 (-175 3675);
PAINT GREEN (-175 3675);
DISPLAY INVISIBLE (-175 3675);
FORCEPROP 1 LAST HDL_TAP TRUE
J 2
(-500 3500);
DISPLAY 0.872340 (-500 3500);
DISPLAY INVISIBLE (-500 3500);
FORCEPROP 1 LAST PATH I83
J 2
(-173 3625);
DISPLAY 0.872340 (-173 3625);
PAINT GREEN (-173 3625);
DISPLAY INVISIBLE (-173 3625);
FORCEADD TAP..1
R 2
(-175 3675);
FORCEPROP 3 LASTPIN (-125 3675) SIG_NAME M_B_CPU0_SA_DQ<25>
J 0
(-115 3685);
DISPLAY 0.659574 (-115 3685);
PAINT MONO (-115 3685);
DISPLAY INVISIBLE (-115 3685);
FORCEPROP 1 LASTPIN (-125 3675) BN 25
J 2
(-113 3683);
DISPLAY 0.680851 (-113 3683);
PAINT GREEN (-113 3683);
FORCEPROP 2 LAST CDS_LIB standard
J 0
(-175 3675);
DISPLAY INVISIBLE (-175 3675);
FORCEPROP 1 LAST BODY_TYPE PLUMBING
J 2
(-175 3725);
DISPLAY 0.872340 (-175 3725);
PAINT GREEN (-175 3725);
DISPLAY INVISIBLE (-175 3725);
FORCEPROP 1 LAST HDL_TAP TRUE
J 2
(-500 3550);
DISPLAY 0.872340 (-500 3550);
DISPLAY INVISIBLE (-500 3550);
FORCEPROP 1 LAST PATH I84
J 2
(-173 3675);
DISPLAY 0.872340 (-173 3675);
PAINT GREEN (-173 3675);
DISPLAY INVISIBLE (-173 3675);
FORCEADD TAP..1
R 2
(-175 3775);
FORCEPROP 3 LASTPIN (-125 3775) SIG_NAME M_B_CPU0_SA_DQ<27>
J 0
(-115 3785);
DISPLAY 0.659574 (-115 3785);
PAINT MONO (-115 3785);
DISPLAY INVISIBLE (-115 3785);
FORCEPROP 1 LASTPIN (-125 3775) BN 27
J 2
(-113 3783);
DISPLAY 0.680851 (-113 3783);
PAINT GREEN (-113 3783);
FORCEPROP 2 LAST CDS_LIB standard
J 0
(-175 3775);
DISPLAY INVISIBLE (-175 3775);
FORCEPROP 1 LAST BODY_TYPE PLUMBING
J 2
(-175 3825);
DISPLAY 0.872340 (-175 3825);
PAINT GREEN (-175 3825);
DISPLAY INVISIBLE (-175 3825);
FORCEPROP 1 LAST HDL_TAP TRUE
J 2
(-500 3650);
DISPLAY 0.872340 (-500 3650);
DISPLAY INVISIBLE (-500 3650);
FORCEPROP 1 LAST PATH I85
J 2
(-173 3775);
DISPLAY 0.872340 (-173 3775);
PAINT GREEN (-173 3775);
DISPLAY INVISIBLE (-173 3775);
FORCEADD TAP..1
R 2
(-175 3825);
FORCEPROP 3 LASTPIN (-125 3825) SIG_NAME M_B_CPU0_SA_DQ<28>
J 0
(-115 3835);
DISPLAY 0.659574 (-115 3835);
PAINT MONO (-115 3835);
DISPLAY INVISIBLE (-115 3835);
FORCEPROP 1 LASTPIN (-125 3825) BN 28
J 2
(-113 3833);
DISPLAY 0.680851 (-113 3833);
PAINT GREEN (-113 3833);
FORCEPROP 2 LAST CDS_LIB standard
J 0
(-175 3825);
DISPLAY INVISIBLE (-175 3825);
FORCEPROP 1 LAST BODY_TYPE PLUMBING
J 2
(-175 3875);
DISPLAY 0.872340 (-175 3875);
PAINT GREEN (-175 3875);
DISPLAY INVISIBLE (-175 3875);
FORCEPROP 1 LAST HDL_TAP TRUE
J 2
(-500 3700);
DISPLAY 0.872340 (-500 3700);
DISPLAY INVISIBLE (-500 3700);
FORCEPROP 1 LAST PATH I86
J 2
(-173 3825);
DISPLAY 0.872340 (-173 3825);
PAINT GREEN (-173 3825);
DISPLAY INVISIBLE (-173 3825);
FORCEADD TAP..1
R 2
(-175 3725);
FORCEPROP 3 LASTPIN (-125 3725) SIG_NAME M_B_CPU0_SA_DQ<26>
J 0
(-115 3735);
DISPLAY 0.659574 (-115 3735);
PAINT MONO (-115 3735);
DISPLAY INVISIBLE (-115 3735);
FORCEPROP 1 LASTPIN (-125 3725) BN 26
J 2
(-113 3733);
DISPLAY 0.680851 (-113 3733);
PAINT GREEN (-113 3733);
FORCEPROP 2 LAST CDS_LIB standard
J 0
(-175 3725);
DISPLAY INVISIBLE (-175 3725);
FORCEPROP 1 LAST BODY_TYPE PLUMBING
J 2
(-175 3775);
DISPLAY 0.872340 (-175 3775);
PAINT GREEN (-175 3775);
DISPLAY INVISIBLE (-175 3775);
FORCEPROP 1 LAST HDL_TAP TRUE
J 2
(-500 3600);
DISPLAY 0.872340 (-500 3600);
DISPLAY INVISIBLE (-500 3600);
FORCEPROP 1 LAST PATH I87
J 2
(-173 3725);
DISPLAY 0.872340 (-173 3725);
PAINT GREEN (-173 3725);
DISPLAY INVISIBLE (-173 3725);
FORCEADD OFFPAGE..3
R 2
(-1200 4000);
FORCEPROP 2 LAST $XR1 85 
J 0
(-1569 4000);
DISPLAY 0.638298 (-1569 4000);
PAINT MONO (-1569 4000);
FORCEPROP 2 LAST $XR0 84 
J 0
(-1479 4000);
DISPLAY 0.638298 (-1479 4000);
PAINT MONO (-1479 4000);
FORCEPROP 2 LAST CDS_LIB standard
J 0
(-1200 4000);
DISPLAY INVISIBLE (-1200 4000);
FORCEPROP 1 LAST OFFPAGE TRUE
J 2
(-1525 3875);
DISPLAY 0.872340 (-1525 3875);
DISPLAY INVISIBLE (-1525 3875);
FORCEPROP 1 LAST COMMENT_BODY TRUE
J 2
(-1150 3900);
DISPLAY 0.872340 (-1150 3900);
PAINT GREEN (-1150 3900);
DISPLAY INVISIBLE (-1150 3900);
FORCEPROP 2 LAST PATH I88
J 0
(-1150 4075);
DISPLAY 1.021277 (-1150 4075);
DISPLAY INVISIBLE (-1150 4075);
FORCEADD TAP..1
R 2
(-175 3875);
FORCEPROP 3 LASTPIN (-125 3875) SIG_NAME M_B_CPU0_SA_DQ<29>
J 0
(-115 3885);
DISPLAY 0.659574 (-115 3885);
PAINT MONO (-115 3885);
DISPLAY INVISIBLE (-115 3885);
FORCEPROP 1 LASTPIN (-125 3875) BN 29
J 2
(-113 3883);
DISPLAY 0.680851 (-113 3883);
PAINT GREEN (-113 3883);
FORCEPROP 2 LAST CDS_LIB standard
J 0
(-175 3875);
DISPLAY INVISIBLE (-175 3875);
FORCEPROP 1 LAST BODY_TYPE PLUMBING
J 2
(-175 3925);
DISPLAY 0.872340 (-175 3925);
PAINT GREEN (-175 3925);
DISPLAY INVISIBLE (-175 3925);
FORCEPROP 1 LAST HDL_TAP TRUE
J 2
(-500 3750);
DISPLAY 0.872340 (-500 3750);
DISPLAY INVISIBLE (-500 3750);
FORCEPROP 1 LAST PATH I89
J 2
(-173 3875);
DISPLAY 0.872340 (-173 3875);
PAINT GREEN (-173 3875);
DISPLAY INVISIBLE (-173 3875);
FORCEADD TAP..1
R 2
(-175 25);
FORCEPROP 3 LASTPIN (-125 25) SIG_NAME M_B_CPU0_SB_CB<0>
J 0
(-115 35);
DISPLAY 0.659574 (-115 35);
PAINT MONO (-115 35);
DISPLAY INVISIBLE (-115 35);
FORCEPROP 1 LASTPIN (-125 25) BN 0
J 2
(-113 33);
DISPLAY 0.680851 (-113 33);
PAINT GREEN (-113 33);
FORCEPROP 2 LAST CDS_LIB standard
J 0
(-175 25);
DISPLAY INVISIBLE (-175 25);
FORCEPROP 1 LAST BODY_TYPE PLUMBING
J 2
(-175 75);
DISPLAY 0.872340 (-175 75);
PAINT GREEN (-175 75);
DISPLAY INVISIBLE (-175 75);
FORCEPROP 1 LAST HDL_TAP TRUE
J 2
(-500 -100);
DISPLAY 0.872340 (-500 -100);
DISPLAY INVISIBLE (-500 -100);
FORCEPROP 1 LAST PATH I9
J 2
(-173 25);
DISPLAY 0.872340 (-173 25);
PAINT GREEN (-173 25);
DISPLAY INVISIBLE (-173 25);
FORCEADD TAP..1
R 2
(-175 3925);
FORCEPROP 3 LASTPIN (-125 3925) SIG_NAME M_B_CPU0_SA_DQ<30>
J 0
(-115 3935);
DISPLAY 0.659574 (-115 3935);
PAINT MONO (-115 3935);
DISPLAY INVISIBLE (-115 3935);
FORCEPROP 1 LASTPIN (-125 3925) BN 30
J 2
(-113 3933);
DISPLAY 0.680851 (-113 3933);
PAINT GREEN (-113 3933);
FORCEPROP 2 LAST CDS_LIB standard
J 0
(-175 3925);
DISPLAY INVISIBLE (-175 3925);
FORCEPROP 1 LAST BODY_TYPE PLUMBING
J 2
(-175 3975);
DISPLAY 0.872340 (-175 3975);
PAINT GREEN (-175 3975);
DISPLAY INVISIBLE (-175 3975);
FORCEPROP 1 LAST HDL_TAP TRUE
J 2
(-500 3800);
DISPLAY 0.872340 (-500 3800);
DISPLAY INVISIBLE (-500 3800);
FORCEPROP 1 LAST PATH I90
J 2
(-173 3925);
DISPLAY 0.872340 (-173 3925);
PAINT GREEN (-173 3925);
DISPLAY INVISIBLE (-173 3925);
FORCEADD TAP..1
R 2
(-175 3975);
FORCEPROP 3 LASTPIN (-125 3975) SIG_NAME M_B_CPU0_SA_DQ<31>
J 0
(-115 3985);
DISPLAY 0.659574 (-115 3985);
PAINT MONO (-115 3985);
DISPLAY INVISIBLE (-115 3985);
FORCEPROP 1 LASTPIN (-125 3975) BN 31
J 2
(-113 3983);
DISPLAY 0.680851 (-113 3983);
PAINT GREEN (-113 3983);
FORCEPROP 2 LAST CDS_LIB standard
J 0
(-175 3975);
DISPLAY INVISIBLE (-175 3975);
FORCEPROP 1 LAST BODY_TYPE PLUMBING
J 2
(-175 4025);
DISPLAY 0.872340 (-175 4025);
PAINT GREEN (-175 4025);
DISPLAY INVISIBLE (-175 4025);
FORCEPROP 1 LAST HDL_TAP TRUE
J 2
(-500 3850);
DISPLAY 0.872340 (-500 3850);
DISPLAY INVISIBLE (-500 3850);
FORCEPROP 1 LAST PATH I91
J 2
(-173 3975);
DISPLAY 0.872340 (-173 3975);
PAINT GREEN (-173 3975);
DISPLAY INVISIBLE (-173 3975);
FORCEADD OFFPAGE..4
(4350 -225);
FORCEPROP 2 LAST $XR1 85 
J 0
(4626 -225);
DISPLAY 0.638298 (4626 -225);
PAINT MONO (4626 -225);
FORCEPROP 2 LAST $XR0 84 
J 0
(4536 -225);
DISPLAY 0.638298 (4536 -225);
PAINT MONO (4536 -225);
FORCEPROP 2 LAST CDS_LIB standard
J 0
(4350 -225);
PAINT MONO (4350 -225);
DISPLAY INVISIBLE (4350 -225);
FORCEPROP 1 LAST OFFPAGE TRUE
J 0
(4675 -350);
DISPLAY 1.170213 (4675 -350);
PAINT GREEN (4675 -350);
DISPLAY INVISIBLE (4675 -350);
FORCEPROP 1 LAST COMMENT_BODY TRUE
J 0
(4325 -325);
DISPLAY 1.170213 (4325 -325);
PAINT GREEN (4325 -325);
DISPLAY INVISIBLE (4325 -325);
FORCEPROP 2 LAST PATH I92
J 0
(4525 -150);
DISPLAY 1.021277 (4525 -150);
DISPLAY INVISIBLE (4525 -150);
FORCEADD TAP..1
(3250 275);
FORCEPROP 3 LASTPIN (3200 275) SIG_NAME M_B_CPU0_SB_CS_N<1>
J 0
(3210 285);
DISPLAY 0.659574 (3210 285);
PAINT MONO (3210 285);
DISPLAY INVISIBLE (3210 285);
FORCEPROP 1 LASTPIN (3200 275) BN 1
J 0
(3188 283);
DISPLAY 0.680851 (3188 283);
PAINT GREEN (3188 283);
FORCEPROP 2 LAST CDS_LIB standard
J 0
(3250 275);
DISPLAY INVISIBLE (3250 275);
FORCEPROP 1 LAST BODY_TYPE PLUMBING
J 0
(3250 325);
DISPLAY 0.872340 (3250 325);
PAINT GREEN (3250 325);
DISPLAY INVISIBLE (3250 325);
FORCEPROP 1 LAST HDL_TAP TRUE
J 0
(3575 150);
DISPLAY 0.872340 (3575 150);
DISPLAY INVISIBLE (3575 150);
FORCEPROP 1 LAST PATH I93
J 0
(3248 275);
DISPLAY 0.872340 (3248 275);
PAINT GREEN (3248 275);
DISPLAY INVISIBLE (3248 275);
FORCEADD TAP..1
(3250 225);
FORCEPROP 3 LASTPIN (3200 225) SIG_NAME M_B_CPU0_SB_CS_N<0>
J 0
(3210 235);
DISPLAY 0.659574 (3210 235);
PAINT MONO (3210 235);
DISPLAY INVISIBLE (3210 235);
FORCEPROP 1 LASTPIN (3200 225) BN 0
J 0
(3188 233);
DISPLAY 0.680851 (3188 233);
PAINT GREEN (3188 233);
FORCEPROP 2 LAST CDS_LIB standard
J 0
(3250 225);
DISPLAY INVISIBLE (3250 225);
FORCEPROP 1 LAST BODY_TYPE PLUMBING
J 0
(3250 275);
DISPLAY 0.872340 (3250 275);
PAINT GREEN (3250 275);
DISPLAY INVISIBLE (3250 275);
FORCEPROP 1 LAST HDL_TAP TRUE
J 0
(3575 100);
DISPLAY 0.872340 (3575 100);
DISPLAY INVISIBLE (3575 100);
FORCEPROP 1 LAST PATH I94
J 0
(3248 225);
DISPLAY 0.872340 (3248 225);
PAINT GREEN (3248 225);
DISPLAY INVISIBLE (3248 225);
FORCEADD TAP..1
(3250 375);
FORCEPROP 3 LASTPIN (3200 375) SIG_NAME M_B_CPU0_SB_CS_N<3>
J 0
(3210 385);
DISPLAY 0.659574 (3210 385);
PAINT MONO (3210 385);
DISPLAY INVISIBLE (3210 385);
FORCEPROP 1 LASTPIN (3200 375) BN 3
J 0
(3188 383);
DISPLAY 0.680851 (3188 383);
PAINT GREEN (3188 383);
FORCEPROP 2 LAST CDS_LIB standard
J 0
(3250 375);
DISPLAY INVISIBLE (3250 375);
FORCEPROP 1 LAST BODY_TYPE PLUMBING
J 0
(3250 425);
DISPLAY 0.872340 (3250 425);
PAINT GREEN (3250 425);
DISPLAY INVISIBLE (3250 425);
FORCEPROP 1 LAST HDL_TAP TRUE
J 0
(3575 250);
DISPLAY 0.872340 (3575 250);
DISPLAY INVISIBLE (3575 250);
FORCEPROP 1 LAST PATH I95
J 0
(3248 375);
DISPLAY 0.872340 (3248 375);
PAINT GREEN (3248 375);
DISPLAY INVISIBLE (3248 375);
FORCEADD TAP..1
(3250 325);
FORCEPROP 3 LASTPIN (3200 325) SIG_NAME M_B_CPU0_SB_CS_N<2>
J 0
(3210 335);
DISPLAY 0.659574 (3210 335);
PAINT MONO (3210 335);
DISPLAY INVISIBLE (3210 335);
FORCEPROP 1 LASTPIN (3200 325) BN 2
J 0
(3188 333);
DISPLAY 0.680851 (3188 333);
PAINT GREEN (3188 333);
FORCEPROP 2 LAST CDS_LIB standard
J 0
(3250 325);
DISPLAY INVISIBLE (3250 325);
FORCEPROP 1 LAST BODY_TYPE PLUMBING
J 0
(3250 375);
DISPLAY 0.872340 (3250 375);
PAINT GREEN (3250 375);
DISPLAY INVISIBLE (3250 375);
FORCEPROP 1 LAST HDL_TAP TRUE
J 0
(3575 200);
DISPLAY 0.872340 (3575 200);
DISPLAY INVISIBLE (3575 200);
FORCEPROP 1 LAST PATH I96
J 0
(3248 325);
DISPLAY 0.872340 (3248 325);
PAINT GREEN (3248 325);
DISPLAY INVISIBLE (3248 325);
FORCEADD TAP..1
(3250 525);
FORCEPROP 3 LASTPIN (3200 525) SIG_NAME M_B_CPU0_SA_CS_N<0>
J 0
(3210 535);
DISPLAY 0.659574 (3210 535);
PAINT MONO (3210 535);
DISPLAY INVISIBLE (3210 535);
FORCEPROP 1 LASTPIN (3200 525) BN 0
J 0
(3188 533);
DISPLAY 0.680851 (3188 533);
PAINT GREEN (3188 533);
FORCEPROP 2 LAST CDS_LIB standard
J 0
(3250 525);
DISPLAY INVISIBLE (3250 525);
FORCEPROP 1 LAST BODY_TYPE PLUMBING
J 0
(3250 575);
DISPLAY 0.872340 (3250 575);
PAINT GREEN (3250 575);
DISPLAY INVISIBLE (3250 575);
FORCEPROP 1 LAST HDL_TAP TRUE
J 0
(3575 400);
DISPLAY 0.872340 (3575 400);
DISPLAY INVISIBLE (3575 400);
FORCEPROP 1 LAST PATH I97
J 0
(3248 525);
DISPLAY 0.872340 (3248 525);
PAINT GREEN (3248 525);
DISPLAY INVISIBLE (3248 525);
FORCEADD TAP..1
(3250 625);
FORCEPROP 3 LASTPIN (3200 625) SIG_NAME M_B_CPU0_SA_CS_N<2>
J 0
(3210 635);
DISPLAY 0.659574 (3210 635);
PAINT MONO (3210 635);
DISPLAY INVISIBLE (3210 635);
FORCEPROP 1 LASTPIN (3200 625) BN 2
J 0
(3188 633);
DISPLAY 0.680851 (3188 633);
PAINT GREEN (3188 633);
FORCEPROP 2 LAST CDS_LIB standard
J 0
(3250 625);
DISPLAY INVISIBLE (3250 625);
FORCEPROP 1 LAST BODY_TYPE PLUMBING
J 0
(3250 675);
DISPLAY 0.872340 (3250 675);
PAINT GREEN (3250 675);
DISPLAY INVISIBLE (3250 675);
FORCEPROP 1 LAST HDL_TAP TRUE
J 0
(3575 500);
DISPLAY 0.872340 (3575 500);
DISPLAY INVISIBLE (3575 500);
FORCEPROP 1 LAST PATH I98
J 0
(3248 625);
DISPLAY 0.872340 (3248 625);
PAINT GREEN (3248 625);
DISPLAY INVISIBLE (3248 625);
FORCEADD TAP..1
(3250 575);
FORCEPROP 3 LASTPIN (3200 575) SIG_NAME M_B_CPU0_SA_CS_N<1>
J 0
(3210 585);
DISPLAY 0.659574 (3210 585);
PAINT MONO (3210 585);
DISPLAY INVISIBLE (3210 585);
FORCEPROP 1 LASTPIN (3200 575) BN 1
J 0
(3188 583);
DISPLAY 0.680851 (3188 583);
PAINT GREEN (3188 583);
FORCEPROP 2 LAST CDS_LIB standard
J 0
(3250 575);
DISPLAY INVISIBLE (3250 575);
FORCEPROP 1 LAST BODY_TYPE PLUMBING
J 0
(3250 625);
DISPLAY 0.872340 (3250 625);
PAINT GREEN (3250 625);
DISPLAY INVISIBLE (3250 625);
FORCEPROP 1 LAST HDL_TAP TRUE
J 0
(3575 450);
DISPLAY 0.872340 (3575 450);
DISPLAY INVISIBLE (3575 450);
FORCEPROP 1 LAST PATH I99
J 0
(3248 575);
DISPLAY 0.872340 (3248 575);
PAINT GREEN (3248 575);
DISPLAY INVISIBLE (3248 575);
FORCEADD QUANTA_TITLE_BLOCK_C..1
(6175 -1525);
FORCEPROP 0 LAST CDS_CON_LAST_MODIFIED Fri Aug 25 14:00:07 2023
J 0
(4290 -1510);
PAINT MONO (4290 -1510);
DISPLAY INVISIBLE (4290 -1510);
FORCEPROP 1 LAST CUSTOM_TXT_CDS <CON_LAST_MODIFIED>
J 0
(4290 -1510);
DISPLAY 0.978723 (4290 -1510);
FORCEPROP 2 LAST CUSTOM_TXT_CDS <XR_PAGE_TITLE>
J 0
(-1715 3725);
DISPLAY 0.638298 (-1715 3725);
PAINT PINK (-1715 3725);
DISPLAY INVISIBLE (-1715 3725);
FORCEPROP 2 LAST CUSTOM_TXT_CDS <CON_PAGE_NUM> OF <CON_TOTAL_PAGES>
J 0
(5725 -1500);
DISPLAY 0.978723 (5725 -1500);
FORCEPROP 2 LAST CUSTOM_TXT_CDS <Q_PROJ>
J 0
(3793 -1423);
DISPLAY 1.212766 (3793 -1423);
FORCEPROP 2 LAST CUSTOM_TXT_CDS <Q_NUMBER>
J 0
(4772 -1422);
DISPLAY 1.212766 (4772 -1422);
FORCEPROP 2 LAST CUSTOM_TXT_CDS <Q_REV>
J 0
(5991 -1422);
DISPLAY 1.212766 (5991 -1422);
FORCEPROP 1 LAST CUSTOM_TXT_CDS <NAME_2>
J 0
(3000 -1475);
FORCEPROP 1 LAST CUSTOM_TXT_CDS <NAME_1>
J 0
(3000 -1350);
FORCEPROP 1 LAST Q_TITLE SPR CPU0 - DDR CH B (9 OF 30)
J 0
(-3191 -1499);
DISPLAY 1.957447 (-3191 -1499);
PAINT GREEN (-3191 -1499);
FORCEPROP 1 LAST Q_DEPT 
J 1
(2412 -1476);
DISPLAY 1.957447 (2412 -1476);
PAINT GREEN (2412 -1476);
FORCEPROP 2 LAST CDS_LIB pure_quanta
J 0
(6175 -1525);
PAINT MONO (6175 -1525);
DISPLAY INVISIBLE (6175 -1525);
FORCEPROP 1 LAST CDS_LMAN_SYM_OUTLINE -9475,6775,100,-125
J 0
(6175 -1525);
DISPLAY 0.468085 (6175 -1525);
PAINT GREEN (6175 -1525);
DISPLAY INVISIBLE (6175 -1525);
FORCEPROP 2 LAST PAGE_BORDER TRUE
J 0
(-1715 3725);
DISPLAY 0.638298 (-1715 3725);
PAINT PINK (-1715 3725);
DISPLAY INVISIBLE (-1715 3725);
FORCEPROP 2 LAST CDS_XR_PAGE_TITLE CR-21 : @S9S_MB_2U_LIB.S9S_MB_2U(SCH_1):PAGE21
J 0
(-1715 3725);
DISPLAY 0.638298 (-1715 3725);
PAINT PINK (-1715 3725);
DISPLAY INVISIBLE (-1715 3725);
FORCEPROP 1 LAST COMMENT_BODY TRUE
J 0
(6187 -1538);
DISPLAY 0.978723 (6187 -1538);
PAINT GREEN (6187 -1538);
DISPLAY INVISIBLE (6187 -1538);
WIRE 17 -1 (3300 1650)(3300 1700);
WIRE 17 -1 (3300 1600)(3300 1650);
WIRE 17 -1 (3300 1700)(4300 1700);
FORCEPROP 2 LAST SIG_NAME M_B_CPU0_SA_CA<6:0>
J 0
(3440 1710);
DISPLAY 0.680851 (3440 1710);
PAINT WHITE (3440 1710);
WIRE 17 -1 (3300 1550)(3300 1600);
WIRE 17 -1 (3300 1500)(3300 1550);
WIRE 17 -1 (3300 1450)(3300 1500);
WIRE 17 -1 (3300 1400)(3300 1450);
WIRE 17 -1 (3300 650)(3300 700);
WIRE 17 -1 (3300 600)(3300 650);
WIRE 17 -1 (3300 700)(4300 700);
FORCEPROP 2 LAST SIG_NAME M_B_CPU0_SA_CS_N<3:0>
J 0
(3440 710);
DISPLAY 0.680851 (3440 710);
PAINT WHITE (3440 710);
WIRE 17 -1 (3300 550)(3300 600);
WIRE 17 -1 (3300 3400)(3300 3450);
WIRE 17 -1 (3300 3350)(3300 3400);
WIRE 17 -1 (3300 3450)(4300 3450);
FORCEPROP 2 LAST SIG_NAME M_B_CPU0_SA_DQS_DN<9:0>
J 0
(3440 3460);
DISPLAY 0.680851 (3440 3460);
PAINT WHITE (3440 3460);
WIRE 17 -1 (3300 3300)(3300 3350);
WIRE 17 -1 (3300 3250)(3300 3300);
WIRE 17 -1 (3300 3200)(3300 3250);
WIRE 17 -1 (3300 3150)(3300 3200);
WIRE 17 -1 (3300 3100)(3300 3150);
WIRE 17 -1 (3300 3050)(3300 3100);
WIRE 17 -1 (3300 3000)(3300 3050);
WIRE 17 -1 (3300 3950)(3300 4000);
WIRE 17 -1 (3300 3900)(3300 3950);
WIRE 17 -1 (3300 4000)(4300 4000);
FORCEPROP 2 LAST SIG_NAME M_B_CPU0_SA_DQS_DP<9:0>
J 0
(3440 4010);
DISPLAY 0.680851 (3440 4010);
PAINT WHITE (3440 4010);
WIRE 17 -1 (3300 3850)(3300 3900);
WIRE 17 -1 (3300 3800)(3300 3850);
WIRE 17 -1 (3300 3750)(3300 3800);
WIRE 17 -1 (3300 3700)(3300 3750);
WIRE 17 -1 (3300 3650)(3300 3700);
WIRE 17 -1 (3300 3600)(3300 3650);
WIRE 17 -1 (3300 3550)(3300 3600);
WIRE 17 -1 (3300 1150)(3300 1200);
WIRE 17 -1 (3300 1100)(3300 1150);
WIRE 17 -1 (3300 1200)(4300 1200);
FORCEPROP 2 LAST SIG_NAME M_B_CPU0_SB_CA<6:0>
J 0
(3440 1210);
DISPLAY 0.680851 (3440 1210);
PAINT WHITE (3440 1210);
WIRE 17 -1 (3300 1050)(3300 1100);
WIRE 17 -1 (3300 1000)(3300 1050);
WIRE 17 -1 (3300 950)(3300 1000);
WIRE 17 -1 (3300 900)(3300 950);
WIRE 17 -1 (3300 350)(3300 400);
WIRE 17 -1 (3300 300)(3300 350);
WIRE 17 -1 (3300 400)(4300 400);
FORCEPROP 2 LAST SIG_NAME M_B_CPU0_SB_CS_N<3:0>
J 0
(3440 410);
DISPLAY 0.680851 (3440 410);
PAINT WHITE (3440 410);
WIRE 17 -1 (3300 250)(3300 300);
WIRE 17 -1 (3300 2250)(3300 2300);
WIRE 17 -1 (3300 2200)(3300 2250);
WIRE 17 -1 (3300 2300)(4300 2300);
FORCEPROP 2 LAST SIG_NAME M_B_CPU0_SB_DQS_DN<9:0>
J 0
(3440 2310);
DISPLAY 0.680851 (3440 2310);
PAINT WHITE (3440 2310);
WIRE 17 -1 (3300 2150)(3300 2200);
WIRE 17 -1 (3300 2100)(3300 2150);
WIRE 17 -1 (3300 2050)(3300 2100);
WIRE 17 -1 (3300 2000)(3300 2050);
WIRE 17 -1 (3300 1950)(3300 2000);
WIRE 17 -1 (3300 1900)(3300 1950);
WIRE 17 -1 (3300 1850)(3300 1900);
WIRE 17 -1 (3300 2800)(3300 2850);
WIRE 17 -1 (3300 2750)(3300 2800);
WIRE 17 -1 (3300 2850)(4300 2850);
FORCEPROP 2 LAST SIG_NAME M_B_CPU0_SB_DQS_DP<9:0>
J 0
(3440 2860);
DISPLAY 0.680851 (3440 2860);
PAINT WHITE (3440 2860);
WIRE 17 -1 (3300 2700)(3300 2750);
WIRE 17 -1 (3300 2650)(3300 2700);
WIRE 17 -1 (3300 2600)(3300 2650);
WIRE 17 -1 (3300 2550)(3300 2600);
WIRE 17 -1 (3300 2500)(3300 2550);
WIRE 17 -1 (3300 2450)(3300 2500);
WIRE 17 -1 (3300 2400)(3300 2450);
WIRE 17 -1 (-225 50)(-225 100);
WIRE 17 -1 (-225 100)(-225 150);
WIRE 17 -1 (-225 150)(-225 200);
WIRE 17 -1 (-225 200)(-225 250);
WIRE 17 -1 (-225 250)(-225 300);
WIRE 17 -1 (-225 300)(-225 350);
WIRE 17 -1 (-225 350)(-225 400);
WIRE 17 -1 (-1150 400)(-225 400);
FORCEPROP 2 LAST SIG_NAME M_B_CPU0_SB_CB<7:0>
J 0
(-1010 410);
DISPLAY 0.680851 (-1010 410);
PAINT WHITE (-1010 410);
WIRE 17 -1 (-225 450)(-225 500);
WIRE 17 -1 (-225 500)(-225 550);
WIRE 17 -1 (-225 550)(-225 600);
WIRE 17 -1 (-225 600)(-225 650);
WIRE 17 -1 (-225 650)(-225 700);
WIRE 17 -1 (-225 700)(-225 750);
WIRE 17 -1 (-225 750)(-225 800);
WIRE 17 -1 (-225 800)(-225 850);
WIRE 17 -1 (-225 850)(-225 900);
WIRE 17 -1 (-225 900)(-225 950);
WIRE 17 -1 (-225 950)(-225 1000);
WIRE 17 -1 (-225 1000)(-225 1050);
WIRE 17 -1 (-225 1050)(-225 1100);
WIRE 17 -1 (-225 1100)(-225 1150);
WIRE 17 -1 (-225 1150)(-225 1200);
WIRE 17 -1 (-225 1200)(-225 1250);
WIRE 17 -1 (-225 1250)(-225 1300);
WIRE 17 -1 (-225 1300)(-225 1350);
WIRE 17 -1 (-225 1350)(-225 1400);
WIRE 17 -1 (-225 1400)(-225 1450);
WIRE 17 -1 (-225 1450)(-225 1500);
WIRE 17 -1 (-225 1500)(-225 1550);
WIRE 17 -1 (-225 1550)(-225 1600);
WIRE 17 -1 (-225 1600)(-225 1650);
WIRE 17 -1 (-225 1650)(-225 1700);
WIRE 17 -1 (-225 1700)(-225 1750);
WIRE 17 -1 (-225 1750)(-225 1800);
WIRE 17 -1 (-225 1800)(-225 1850);
WIRE 17 -1 (-225 1850)(-225 1900);
WIRE 17 -1 (-225 1900)(-225 1950);
WIRE 17 -1 (-225 1950)(-225 2000);
WIRE 17 -1 (-1150 2000)(-225 2000);
FORCEPROP 2 LAST SIG_NAME M_B_CPU0_SB_DQ<31:0>
J 0
(-1010 2010);
DISPLAY 0.680851 (-1010 2010);
PAINT WHITE (-1010 2010);
WIRE 17 -1 (-225 2050)(-225 2100);
WIRE 17 -1 (-225 2100)(-225 2150);
WIRE 17 -1 (-225 2150)(-225 2200);
WIRE 17 -1 (-225 2200)(-225 2250);
WIRE 17 -1 (-225 2250)(-225 2300);
WIRE 17 -1 (-225 2300)(-225 2350);
WIRE 17 -1 (-225 2350)(-225 2400);
WIRE 17 -1 (-1150 2400)(-225 2400);
FORCEPROP 2 LAST SIG_NAME M_B_CPU0_SA_CB<7:0>
J 0
(-1010 2410);
DISPLAY 0.680851 (-1010 2410);
PAINT WHITE (-1010 2410);
WIRE 17 -1 (-225 2450)(-225 2500);
WIRE 17 -1 (-225 2500)(-225 2550);
WIRE 17 -1 (-225 2550)(-225 2600);
WIRE 17 -1 (-225 2600)(-225 2650);
WIRE 17 -1 (-225 2650)(-225 2700);
WIRE 17 -1 (-225 2700)(-225 2750);
WIRE 17 -1 (-225 2750)(-225 2800);
WIRE 17 -1 (-225 2800)(-225 2850);
WIRE 17 -1 (-225 2850)(-225 2900);
WIRE 17 -1 (-225 2900)(-225 2950);
WIRE 17 -1 (-225 2950)(-225 3000);
WIRE 17 -1 (-225 3000)(-225 3050);
WIRE 17 -1 (-225 3050)(-225 3100);
WIRE 17 -1 (-225 3100)(-225 3150);
WIRE 17 -1 (-225 3150)(-225 3200);
WIRE 17 -1 (-225 3200)(-225 3250);
WIRE 17 -1 (-225 3250)(-225 3300);
WIRE 17 -1 (-225 3300)(-225 3350);
WIRE 17 -1 (-225 3350)(-225 3400);
WIRE 17 -1 (-225 3400)(-225 3450);
WIRE 17 -1 (-225 3450)(-225 3500);
WIRE 17 -1 (-225 3500)(-225 3550);
WIRE 17 -1 (-225 3550)(-225 3600);
WIRE 17 -1 (-225 3600)(-225 3650);
WIRE 17 -1 (-225 3650)(-225 3700);
WIRE 17 -1 (-225 3700)(-225 3750);
WIRE 17 -1 (-225 3750)(-225 3800);
WIRE 17 -1 (-225 3800)(-225 3850);
WIRE 17 -1 (-225 3850)(-225 3900);
WIRE 17 -1 (-225 3900)(-225 3950);
WIRE 17 -1 (-225 3950)(-225 4000);
WIRE 17 -1 (-1150 4000)(-225 4000);
FORCEPROP 2 LAST SIG_NAME M_B_CPU0_SA_DQ<31:0>
J 0
(-1010 4010);
DISPLAY 0.680851 (-1010 4010);
PAINT WHITE (-1010 4010);
WIRE 17 -1 (-225 -100)(-225 -50);
WIRE 17 -1 (-1150 -50)(-225 -50);
FORCEPROP 2 LAST SIG_NAME M_B_CPU0_CLK_DP<1:0>
J 0
(-1010 -40);
DISPLAY 0.680851 (-1010 -40);
PAINT WHITE (-1010 -40);
WIRE 17 -1 (-225 -200)(-225 -150);
WIRE 17 -1 (-1150 -150)(-225 -150);
FORCEPROP 2 LAST SIG_NAME M_B_CPU0_CLK_DN<1:0>
J 0
(-1010 -140);
DISPLAY 0.680851 (-1010 -140);
PAINT WHITE (-1010 -140);
WIRE 16 -1 (-125 -175)(325 -175);
WIRE 16 -1 (-125 -225)(325 -225);
WIRE 16 -1 (-125 -75)(325 -75);
WIRE 16 -1 (-125 -125)(325 -125);
WIRE 16 -1 (-125 3975)(325 3975);
WIRE 16 -1 (-125 3925)(325 3925);
WIRE 16 -1 (-125 3875)(325 3875);
WIRE 16 -1 (-125 3825)(325 3825);
WIRE 16 -1 (-125 3775)(325 3775);
WIRE 16 -1 (-125 3725)(325 3725);
WIRE 16 -1 (-125 3675)(325 3675);
WIRE 16 -1 (-125 3625)(325 3625);
WIRE 16 -1 (-125 3575)(325 3575);
WIRE 16 -1 (-125 3525)(325 3525);
WIRE 16 -1 (-125 3475)(325 3475);
WIRE 16 -1 (-125 3425)(325 3425);
WIRE 16 -1 (-125 3375)(325 3375);
WIRE 16 -1 (-125 3325)(325 3325);
WIRE 16 -1 (-125 3275)(325 3275);
WIRE 16 -1 (-125 3225)(325 3225);
WIRE 16 -1 (-125 3175)(325 3175);
WIRE 16 -1 (-125 3125)(325 3125);
WIRE 16 -1 (-125 3075)(325 3075);
WIRE 16 -1 (-125 3025)(325 3025);
WIRE 16 -1 (-125 2975)(325 2975);
WIRE 16 -1 (-125 2925)(325 2925);
WIRE 16 -1 (-125 2875)(325 2875);
WIRE 16 -1 (-125 2825)(325 2825);
WIRE 16 -1 (-125 2775)(325 2775);
WIRE 16 -1 (-125 2725)(325 2725);
WIRE 16 -1 (-125 2675)(325 2675);
WIRE 16 -1 (-125 2625)(325 2625);
WIRE 16 -1 (-125 2575)(325 2575);
WIRE 16 -1 (-125 2525)(325 2525);
WIRE 16 -1 (-125 2475)(325 2475);
WIRE 16 -1 (-125 2425)(325 2425);
WIRE 16 -1 (-125 2375)(325 2375);
WIRE 16 -1 (-125 2325)(325 2325);
WIRE 16 -1 (-125 2275)(325 2275);
WIRE 16 -1 (-125 2225)(325 2225);
WIRE 16 -1 (-125 2175)(325 2175);
WIRE 16 -1 (-125 2125)(325 2125);
WIRE 16 -1 (-125 2075)(325 2075);
WIRE 16 -1 (-125 2025)(325 2025);
WIRE 16 -1 (-125 1975)(325 1975);
WIRE 16 -1 (-125 1925)(325 1925);
WIRE 16 -1 (-125 1875)(325 1875);
WIRE 16 -1 (-125 1825)(325 1825);
WIRE 16 -1 (-125 1775)(325 1775);
WIRE 16 -1 (-125 1725)(325 1725);
WIRE 16 -1 (-125 1675)(325 1675);
WIRE 16 -1 (-125 1625)(325 1625);
WIRE 16 -1 (-125 1575)(325 1575);
WIRE 16 -1 (-125 1525)(325 1525);
WIRE 16 -1 (-125 1475)(325 1475);
WIRE 16 -1 (-125 1425)(325 1425);
WIRE 16 -1 (-125 1375)(325 1375);
WIRE 16 -1 (-125 1325)(325 1325);
WIRE 16 -1 (-125 1275)(325 1275);
WIRE 16 -1 (-125 1225)(325 1225);
WIRE 16 -1 (-125 1175)(325 1175);
WIRE 16 -1 (-125 1125)(325 1125);
WIRE 16 -1 (-125 1075)(325 1075);
WIRE 16 -1 (-125 1025)(325 1025);
WIRE 16 -1 (-125 975)(325 975);
WIRE 16 -1 (-125 925)(325 925);
WIRE 16 -1 (-125 875)(325 875);
WIRE 16 -1 (-125 825)(325 825);
WIRE 16 -1 (-125 775)(325 775);
WIRE 16 -1 (-125 725)(325 725);
WIRE 16 -1 (-125 675)(325 675);
WIRE 16 -1 (-125 625)(325 625);
WIRE 16 -1 (-125 575)(325 575);
WIRE 16 -1 (-125 525)(325 525);
WIRE 16 -1 (-125 475)(325 475);
WIRE 16 -1 (-125 425)(325 425);
WIRE 16 -1 (-125 375)(325 375);
WIRE 16 -1 (-125 325)(325 325);
WIRE 16 -1 (-125 275)(325 275);
WIRE 16 -1 (-125 225)(325 225);
WIRE 16 -1 (-125 175)(325 175);
WIRE 16 -1 (-125 125)(325 125);
WIRE 16 -1 (-125 75)(325 75);
WIRE 16 -1 (-125 25)(325 25);
WIRE 16 -1 (4300 825)(2775 825);
FORCEPROP 2 LAST SIG_NAME M_B_CPU0_SB_PAR
J 0
(3409 834);
DISPLAY 0.680851 (3409 834);
PAINT WHITE (3409 834);
WIRE 16 -1 (2775 2375)(3200 2375);
WIRE 16 -1 (2775 2425)(3200 2425);
WIRE 16 -1 (2775 2475)(3200 2475);
WIRE 16 -1 (2775 2525)(3200 2525);
WIRE 16 -1 (2775 2575)(3200 2575);
WIRE 16 -1 (2775 2625)(3200 2625);
WIRE 16 -1 (2775 2675)(3200 2675);
WIRE 16 -1 (2775 2725)(3200 2725);
WIRE 16 -1 (2775 2775)(3200 2775);
WIRE 16 -1 (2775 2825)(3200 2825);
WIRE 16 -1 (2775 1825)(3200 1825);
WIRE 16 -1 (2775 1875)(3200 1875);
WIRE 16 -1 (2775 1925)(3200 1925);
WIRE 16 -1 (2775 1975)(3200 1975);
WIRE 16 -1 (2775 2025)(3200 2025);
WIRE 16 -1 (2775 2075)(3200 2075);
WIRE 16 -1 (2775 2125)(3200 2125);
WIRE 16 -1 (2775 2175)(3200 2175);
WIRE 16 -1 (2775 2225)(3200 2225);
WIRE 16 -1 (2775 2275)(3200 2275);
WIRE 16 -1 (2775 225)(3200 225);
WIRE 16 -1 (2775 275)(3200 275);
WIRE 16 -1 (2775 325)(3200 325);
WIRE 16 -1 (2775 375)(3200 375);
WIRE 16 -1 (2775 875)(3200 875);
WIRE 16 -1 (2775 925)(3200 925);
WIRE 16 -1 (2775 975)(3200 975);
WIRE 16 -1 (2775 1025)(3200 1025);
WIRE 16 -1 (2775 1075)(3200 1075);
WIRE 16 -1 (2775 1125)(3200 1125);
WIRE 16 -1 (2775 1175)(3200 1175);
WIRE 16 -1 (4300 1325)(2775 1325);
FORCEPROP 2 LAST SIG_NAME M_B_CPU0_SA_PAR
J 0
(3409 1334);
DISPLAY 0.680851 (3409 1334);
PAINT WHITE (3409 1334);
WIRE 16 -1 (2775 3525)(3200 3525);
WIRE 16 -1 (2775 3575)(3200 3575);
WIRE 16 -1 (2775 3625)(3200 3625);
WIRE 16 -1 (2775 3675)(3200 3675);
WIRE 16 -1 (2775 3725)(3200 3725);
WIRE 16 -1 (2775 3775)(3200 3775);
WIRE 16 -1 (2775 3825)(3200 3825);
WIRE 16 -1 (2775 3875)(3200 3875);
WIRE 16 -1 (2775 3925)(3200 3925);
WIRE 16 -1 (2775 3975)(3200 3975);
WIRE 16 -1 (2775 2975)(3200 2975);
WIRE 16 -1 (2775 3025)(3200 3025);
WIRE 16 -1 (2775 3075)(3200 3075);
WIRE 16 -1 (2775 3125)(3200 3125);
WIRE 16 -1 (2775 3175)(3200 3175);
WIRE 16 -1 (2775 3225)(3200 3225);
WIRE 16 -1 (2775 3275)(3200 3275);
WIRE 16 -1 (2775 3325)(3200 3325);
WIRE 16 -1 (2775 3375)(3200 3375);
WIRE 16 -1 (2775 3425)(3200 3425);
WIRE 16 -1 (2775 525)(3200 525);
WIRE 16 -1 (2775 575)(3200 575);
WIRE 16 -1 (2775 625)(3200 625);
WIRE 16 -1 (2775 675)(3200 675);
WIRE 16 -1 (2775 1375)(3200 1375);
WIRE 16 -1 (2775 1425)(3200 1425);
WIRE 16 -1 (2775 1475)(3200 1475);
WIRE 16 -1 (2775 1525)(3200 1525);
WIRE 16 -1 (2775 1575)(3200 1575);
WIRE 16 -1 (2775 1625)(3200 1625);
WIRE 16 -1 (2775 1675)(3200 1675);
WIRE 16 -1 (4300 -125)(2775 -125);
FORCEPROP 2 LAST SIG_NAME M_B_CPU0_SB_RSP<0>
J 0
(3409 -116);
DISPLAY 0.680851 (3409 -116);
PAINT WHITE (3409 -116);
WIRE 16 -1 (4300 -75)(2775 -75);
FORCEPROP 2 LAST SIG_NAME M_B_CPU0_SB_RSP<1>
J 0
(3409 -66);
DISPLAY 0.680851 (3409 -66);
PAINT WHITE (3409 -66);
WIRE 16 -1 (4300 25)(2775 25);
FORCEPROP 2 LAST SIG_NAME M_B_CPU0_SA_RSP<0>
J 0
(3409 34);
DISPLAY 0.680851 (3409 34);
PAINT WHITE (3409 34);
WIRE 16 -1 (4300 75)(2775 75);
FORCEPROP 2 LAST SIG_NAME M_B_CPU0_SA_RSP<1>
J 0
(3409 84);
DISPLAY 0.680851 (3409 84);
PAINT WHITE (3409 84);
WIRE 16 -1 (4300 -225)(2775 -225);
FORCEPROP 2 LAST SIG_NAME M_B_CPU0_ALERT_N
J 0
(3409 -216);
DISPLAY 0.680851 (3409 -216);
PAINT WHITE (3409 -216);
QUIT
